FILE_TYPE = MACRO_DRAWING;
SET COLOR_WIRE YELLOW;
SET COLOR_PROP ORANGE;
SET COLOR_DOT WHITE;
SET COLOR_ARC YELLOW;
SET COLOR_BODY GREEN;
SET COLOR_NOTE PURPLE;
SET PROP_DISPLAY VALUE;
SET PAGE_NUMBER P245;
FORCEADD Q_CAP..1
(-4050 200);
FORCEPROP 1 LAST PART_NUMBER CH6223MEA01
J 0
(-4000 50);
DISPLAY 0.489362 (-4000 50);
PAINT BLUE (-4000 50);
DISPLAY INVISIBLE (-4000 50);
FORCEPROP 1 LAST VALUE 22UF
J 0
(-4000 250);
DISPLAY 0.617021 (-4000 250);
PAINT SKYBLUE (-4000 250);
FORCEPROP 1 LAST VOLTAGE 16V
J 0
(-4000 200);
DISPLAY 0.617021 (-4000 200);
PAINT SKYBLUE (-4000 200);
FORCEPROP 1 LAST MATERIAL X6S
J 0
(-4000 100);
DISPLAY 0.617021 (-4000 100);
PAINT SKYBLUE (-4000 100);
FORCEPROP 1 LAST PACK_TYPE C0805
J 0
(-4000 0);
DISPLAY 0.617021 (-4000 0);
PAINT SKYBLUE (-4000 0);
FORCEPROP 1 LAST TOLERANCE 20%
J 0
(-4000 150);
DISPLAY 0.617021 (-4000 150);
PAINT SKYBLUE (-4000 150);
FORCEPROP 1 LAST LOCATION PC2260
J 0
(-4000 300);
DISPLAY 0.617021 (-4000 300);
PAINT AQUA (-4000 300);
FORCEPROP 1 LASTPIN (-4050 300) $PN 1
J 0
(-4040 280);
DISPLAY 0.787234 (-4040 280);
PAINT MONO (-4040 280);
FORCEPROP 1 LASTPIN (-4050 100) $PN 2
J 0
(-4040 80);
DISPLAY 0.787234 (-4040 80);
PAINT MONO (-4040 80);
FORCEPROP 2 LAST CDS_LIB pure_quanta
J 0
(-4050 200);
DISPLAY INVISIBLE (-4050 200);
FORCEPROP 1 LAST PATH I100
J 0
(-4000 350);
DISPLAY 0.978723 (-4000 350);
PAINT WHITE (-4000 350);
DISPLAY INVISIBLE (-4000 350);
FORCEPROP 0 LAST $SEC 1
J 0
(-4000 350);
DISPLAY 0.680851 (-4000 350);
PAINT MONO (-4000 350);
DISPLAY INVISIBLE (-4000 350);
FORCEPROP 0 LAST CDS_SEC 1
J 0
(-4000 350);
DISPLAY 1.021277 (-4000 350);
DISPLAY INVISIBLE (-4000 350);
FORCEADD Q_CAP..1
(-3725 200);
FORCEPROP 1 LAST PART_NUMBER CH6223MEA01
J 0
(-3675 50);
DISPLAY 0.489362 (-3675 50);
PAINT BLUE (-3675 50);
DISPLAY INVISIBLE (-3675 50);
FORCEPROP 1 LAST VOLTAGE 16V
J 0
(-3675 200);
DISPLAY 0.617021 (-3675 200);
PAINT SKYBLUE (-3675 200);
FORCEPROP 1 LAST MATERIAL X6S
J 0
(-3675 100);
DISPLAY 0.617021 (-3675 100);
PAINT SKYBLUE (-3675 100);
FORCEPROP 1 LAST VALUE 22UF
J 0
(-3675 250);
DISPLAY 0.617021 (-3675 250);
PAINT SKYBLUE (-3675 250);
FORCEPROP 1 LAST PACK_TYPE C0805
J 0
(-3675 0);
DISPLAY 0.617021 (-3675 0);
PAINT SKYBLUE (-3675 0);
FORCEPROP 1 LAST TOLERANCE 20%
J 0
(-3675 150);
DISPLAY 0.617021 (-3675 150);
PAINT SKYBLUE (-3675 150);
FORCEPROP 1 LAST LOCATION PC2261
J 0
(-3675 300);
DISPLAY 0.617021 (-3675 300);
PAINT AQUA (-3675 300);
FORCEPROP 1 LASTPIN (-3725 300) $PN 1
J 0
(-3715 280);
DISPLAY 0.787234 (-3715 280);
PAINT MONO (-3715 280);
FORCEPROP 1 LASTPIN (-3725 100) $PN 2
J 0
(-3715 80);
DISPLAY 0.787234 (-3715 80);
PAINT MONO (-3715 80);
FORCEPROP 2 LAST CDS_LIB pure_quanta
J 0
(-3725 200);
DISPLAY INVISIBLE (-3725 200);
FORCEPROP 1 LAST PATH I101
J 0
(-3675 350);
DISPLAY 0.978723 (-3675 350);
PAINT WHITE (-3675 350);
DISPLAY INVISIBLE (-3675 350);
FORCEPROP 0 LAST $SEC 1
J 0
(-3675 350);
DISPLAY 0.680851 (-3675 350);
PAINT MONO (-3675 350);
DISPLAY INVISIBLE (-3675 350);
FORCEPROP 0 LAST CDS_SEC 1
J 0
(-3675 350);
DISPLAY 1.021277 (-3675 350);
DISPLAY INVISIBLE (-3675 350);
FORCEADD GND..1
(-3975 475);
FORCEPROP 3 LASTPIN (-3975 525) SIG_NAME GND\g
J 0
(-3965 535);
DISPLAY 0.659574 (-3965 535);
PAINT MONO (-3965 535);
DISPLAY INVISIBLE (-3965 535);
FORCEPROP 1 LAST HDL_POWER GND
J 0
(-3975 625);
DISPLAY 0.872340 (-3975 625);
PAINT GREEN (-3975 625);
DISPLAY INVISIBLE (-3975 625);
FORCEPROP 2 LAST CDS_LIB logical_power
J 0
(-3975 475);
PAINT MONO (-3975 475);
DISPLAY INVISIBLE (-3975 475);
FORCEPROP 1 LAST SIZE 1B
J 0
(-3900 425);
DISPLAY 0.872340 (-3900 425);
PAINT AQUA (-3900 425);
DISPLAY INVISIBLE (-3900 425);
FORCEPROP 1 LAST PATH I102
J 0
(-3900 475);
DISPLAY 0.872340 (-3900 475);
PAINT AQUA (-3900 475);
DISPLAY INVISIBLE (-3900 475);
FORCEADD Q_CAPP..1
(-3975 850);
FORCEPROP 1 LAST PART_NUMBER CC72703MD38
J 0
(-3925 675);
DISPLAY 0.489362 (-3925 675);
PAINT BLUE (-3925 675);
DISPLAY INVISIBLE (-3925 675);
FORCEPROP 1 LAST VALUE 270UF
J 0
(-3925 925);
DISPLAY 0.617021 (-3925 925);
PAINT SKYBLUE (-3925 925);
FORCEPROP 1 LAST PACK_TYPE THLF
J 0
(-3925 725);
DISPLAY 0.617021 (-3925 725);
PAINT SKYBLUE (-3925 725);
FORCEPROP 1 LAST MATERIAL OSCON
J 0
(-3925 775);
DISPLAY 0.617021 (-3925 775);
PAINT SKYBLUE (-3925 775);
FORCEPROP 1 LAST VOLTAGE 16V
J 0
(-3925 825);
DISPLAY 0.617021 (-3925 825);
PAINT SKYBLUE (-3925 825);
FORCEPROP 1 LAST TOLERANCE 20%
J 0
(-3925 875);
DISPLAY 0.617021 (-3925 875);
PAINT SKYBLUE (-3925 875);
FORCEPROP 1 LAST LOCATION PC3
J 0
(-3925 975);
DISPLAY 0.617021 (-3925 975);
PAINT AQUA (-3925 975);
FORCEPROP 1 LASTPIN (-3975 950) $PN 1
J 0
(-3965 935);
DISPLAY 0.787234 (-3965 935);
PAINT MONO (-3965 935);
FORCEPROP 1 LASTPIN (-3975 750) $PN 2
J 0
(-3965 735);
DISPLAY 0.787234 (-3965 735);
PAINT MONO (-3965 735);
FORCEPROP 2 LAST CDS_LIB pure_quanta
J 0
(-3975 850);
DISPLAY INVISIBLE (-3975 850);
FORCEPROP 1 LAST PATH I103
J 0
(-3925 1000);
DISPLAY 0.978723 (-3925 1000);
DISPLAY INVISIBLE (-3925 1000);
FORCEPROP 1 LAST LOCATION PC3
J 0
(-3925 1025);
DISPLAY 1.021277 (-3925 1025);
PAINT AQUA (-3925 1025);
DISPLAY INVISIBLE (-3925 1025);
FORCEPROP 0 LAST $SEC 1
J 0
(-3925 1025);
DISPLAY 0.680851 (-3925 1025);
PAINT MONO (-3925 1025);
DISPLAY INVISIBLE (-3925 1025);
FORCEPROP 0 LAST CDS_SEC 1
J 0
(-3925 1025);
DISPLAY 1.021277 (-3925 1025);
DISPLAY INVISIBLE (-3925 1025);
FORCEADD Q_CAPP..1
(-3675 850);
FORCEPROP 1 LAST PART_NUMBER CC72703MD38
J 0
(-3625 675);
DISPLAY 0.489362 (-3625 675);
PAINT BLUE (-3625 675);
DISPLAY INVISIBLE (-3625 675);
FORCEPROP 1 LAST TOLERANCE 20%
J 0
(-3625 875);
DISPLAY 0.617021 (-3625 875);
PAINT SKYBLUE (-3625 875);
FORCEPROP 1 LAST VALUE 270UF
J 0
(-3625 925);
DISPLAY 0.617021 (-3625 925);
PAINT SKYBLUE (-3625 925);
FORCEPROP 1 LAST PACK_TYPE THLF
J 0
(-3625 725);
DISPLAY 0.617021 (-3625 725);
PAINT SKYBLUE (-3625 725);
FORCEPROP 1 LAST VOLTAGE 16V
J 0
(-3625 825);
DISPLAY 0.617021 (-3625 825);
PAINT SKYBLUE (-3625 825);
FORCEPROP 1 LAST MATERIAL OSCON
J 0
(-3625 775);
DISPLAY 0.617021 (-3625 775);
PAINT SKYBLUE (-3625 775);
FORCEPROP 1 LAST LOCATION PC566
J 0
(-3625 975);
DISPLAY 0.617021 (-3625 975);
PAINT AQUA (-3625 975);
FORCEPROP 1 LASTPIN (-3675 950) $PN 1
J 0
(-3665 935);
DISPLAY 0.617021 (-3665 935);
PAINT MONO (-3665 935);
FORCEPROP 1 LASTPIN (-3675 750) $PN 2
J 0
(-3665 735);
DISPLAY 0.617021 (-3665 735);
PAINT MONO (-3665 735);
FORCEPROP 2 LAST CDS_LIB pure_quanta
J 0
(-3675 850);
DISPLAY INVISIBLE (-3675 850);
FORCEPROP 1 LAST PATH I104
J 0
(-3625 1000);
DISPLAY 0.978723 (-3625 1000);
DISPLAY INVISIBLE (-3625 1000);
FORCEPROP 1 LAST LOCATION PC566
J 0
(-3625 1025);
DISPLAY 1.021277 (-3625 1025);
PAINT AQUA (-3625 1025);
DISPLAY INVISIBLE (-3625 1025);
FORCEPROP 0 LAST $SEC 1
J 0
(-3625 1025);
DISPLAY 0.680851 (-3625 1025);
PAINT MONO (-3625 1025);
DISPLAY INVISIBLE (-3625 1025);
FORCEPROP 0 LAST CDS_SEC 1
J 0
(-3625 1025);
DISPLAY 1.021277 (-3625 1025);
DISPLAY INVISIBLE (-3625 1025);
FORCEADD Q_CAP..1
(-3400 200);
FORCEPROP 1 LAST PART_NUMBER CH6223MEA01
J 0
(-3350 50);
DISPLAY 0.489362 (-3350 50);
PAINT BLUE (-3350 50);
DISPLAY INVISIBLE (-3350 50);
FORCEPROP 1 LAST VALUE 22UF
J 0
(-3350 250);
DISPLAY 0.617021 (-3350 250);
PAINT SKYBLUE (-3350 250);
FORCEPROP 1 LAST PACK_TYPE C0805
J 0
(-3350 0);
DISPLAY 0.617021 (-3350 0);
PAINT SKYBLUE (-3350 0);
FORCEPROP 1 LAST VOLTAGE 16V
J 0
(-3350 200);
DISPLAY 0.617021 (-3350 200);
PAINT SKYBLUE (-3350 200);
FORCEPROP 1 LAST TOLERANCE 20%
J 0
(-3350 150);
DISPLAY 0.617021 (-3350 150);
PAINT SKYBLUE (-3350 150);
FORCEPROP 1 LAST MATERIAL X6S
J 0
(-3350 100);
DISPLAY 0.617021 (-3350 100);
PAINT SKYBLUE (-3350 100);
FORCEPROP 1 LAST LOCATION PC2262
J 0
(-3350 300);
DISPLAY 0.617021 (-3350 300);
PAINT AQUA (-3350 300);
FORCEPROP 1 LASTPIN (-3400 300) $PN 1
J 0
(-3390 280);
DISPLAY 0.787234 (-3390 280);
PAINT MONO (-3390 280);
FORCEPROP 1 LASTPIN (-3400 100) $PN 2
J 0
(-3390 80);
DISPLAY 0.787234 (-3390 80);
PAINT MONO (-3390 80);
FORCEPROP 2 LAST CDS_LIB pure_quanta
J 0
(-3400 200);
DISPLAY INVISIBLE (-3400 200);
FORCEPROP 1 LAST PATH I105
J 0
(-3350 350);
DISPLAY 0.978723 (-3350 350);
PAINT WHITE (-3350 350);
DISPLAY INVISIBLE (-3350 350);
FORCEPROP 0 LAST $SEC 1
J 0
(-3350 350);
DISPLAY 0.680851 (-3350 350);
PAINT MONO (-3350 350);
DISPLAY INVISIBLE (-3350 350);
FORCEPROP 0 LAST CDS_SEC 1
J 0
(-3350 350);
DISPLAY 1.021277 (-3350 350);
DISPLAY INVISIBLE (-3350 350);
FORCEADD Q_CAP..1
(-3350 850);
FORCEPROP 1 LAST PART_NUMBER CH6223MEA01
J 0
(-3300 700);
DISPLAY 0.489362 (-3300 700);
PAINT BLUE (-3300 700);
DISPLAY INVISIBLE (-3300 700);
FORCEPROP 1 LAST MATERIAL X6S
J 0
(-3300 750);
DISPLAY 0.617021 (-3300 750);
PAINT SKYBLUE (-3300 750);
FORCEPROP 1 LAST TOLERANCE 20%
J 0
(-3300 800);
DISPLAY 0.617021 (-3300 800);
PAINT SKYBLUE (-3300 800);
FORCEPROP 1 LAST PACK_TYPE C0805
J 0
(-3300 650);
DISPLAY 0.617021 (-3300 650);
PAINT SKYBLUE (-3300 650);
FORCEPROP 1 LAST VOLTAGE 16V
J 0
(-3300 850);
DISPLAY 0.617021 (-3300 850);
PAINT SKYBLUE (-3300 850);
FORCEPROP 1 LAST VALUE 22UF
J 0
(-3300 900);
DISPLAY 0.617021 (-3300 900);
PAINT SKYBLUE (-3300 900);
FORCEPROP 1 LAST LOCATION PC567
J 0
(-3300 950);
DISPLAY 0.617021 (-3300 950);
PAINT AQUA (-3300 950);
FORCEPROP 2 LAST CDS_LIB pure_quanta
J 0
(-3350 850);
DISPLAY INVISIBLE (-3350 850);
FORCEPROP 1 LAST PATH I106
J 0
(-3300 1000);
DISPLAY 0.978723 (-3300 1000);
PAINT WHITE (-3300 1000);
DISPLAY INVISIBLE (-3300 1000);
FORCEPROP 0 LAST $SEC 1
J 0
(-3300 1000);
DISPLAY 0.680851 (-3300 1000);
PAINT MONO (-3300 1000);
DISPLAY INVISIBLE (-3300 1000);
FORCEPROP 2 LAST CDS_SEC 1
J 0
(-3300 1050);
DISPLAY 1.021277 (-3300 1050);
DISPLAY INVISIBLE (-3300 1050);
FORCEPROP 1 LASTPIN (-3350 950) $PN 1
J 0
(-3340 930);
DISPLAY 0.787234 (-3340 930);
PAINT MONO (-3340 930);
DISPLAY INVISIBLE (-3340 930);
FORCEPROP 1 LASTPIN (-3350 750) $PN 2
J 0
(-3340 730);
DISPLAY 0.787234 (-3340 730);
PAINT MONO (-3340 730);
DISPLAY INVISIBLE (-3340 730);
FORCEADD Q_CAP..1
(-3075 200);
FORCEPROP 1 LAST PART_NUMBER CH6223MEA01
J 0
(-3025 50);
DISPLAY 0.489362 (-3025 50);
PAINT BLUE (-3025 50);
DISPLAY INVISIBLE (-3025 50);
FORCEPROP 1 LAST PACK_TYPE C0805
J 0
(-3025 0);
DISPLAY 0.617021 (-3025 0);
PAINT SKYBLUE (-3025 0);
FORCEPROP 1 LAST VALUE 22UF
J 0
(-3025 250);
DISPLAY 0.617021 (-3025 250);
PAINT SKYBLUE (-3025 250);
FORCEPROP 1 LAST VOLTAGE 16V
J 0
(-3025 200);
DISPLAY 0.617021 (-3025 200);
PAINT SKYBLUE (-3025 200);
FORCEPROP 1 LAST TOLERANCE 20%
J 0
(-3025 150);
DISPLAY 0.617021 (-3025 150);
PAINT SKYBLUE (-3025 150);
FORCEPROP 1 LAST MATERIAL X6S
J 0
(-3025 100);
DISPLAY 0.617021 (-3025 100);
PAINT SKYBLUE (-3025 100);
FORCEPROP 1 LAST LOCATION PC2263
J 0
(-3025 300);
DISPLAY 0.617021 (-3025 300);
PAINT AQUA (-3025 300);
FORCEPROP 1 LASTPIN (-3075 300) $PN 1
J 0
(-3065 280);
DISPLAY 0.787234 (-3065 280);
PAINT MONO (-3065 280);
FORCEPROP 1 LASTPIN (-3075 100) $PN 2
J 0
(-3065 80);
DISPLAY 0.787234 (-3065 80);
PAINT MONO (-3065 80);
FORCEPROP 2 LAST CDS_LIB pure_quanta
J 0
(-3075 200);
DISPLAY INVISIBLE (-3075 200);
FORCEPROP 1 LAST PATH I107
J 0
(-3025 350);
DISPLAY 0.978723 (-3025 350);
PAINT WHITE (-3025 350);
DISPLAY INVISIBLE (-3025 350);
FORCEPROP 0 LAST $SEC 1
J 0
(-3025 350);
DISPLAY 0.680851 (-3025 350);
PAINT MONO (-3025 350);
DISPLAY INVISIBLE (-3025 350);
FORCEPROP 0 LAST CDS_SEC 1
J 0
(-3025 350);
DISPLAY 1.021277 (-3025 350);
DISPLAY INVISIBLE (-3025 350);
FORCEADD Q_CAP..1
(-2750 200);
FORCEPROP 1 LAST PART_NUMBER CH6223MEA01
J 0
(-2700 50);
DISPLAY 0.489362 (-2700 50);
PAINT BLUE (-2700 50);
DISPLAY INVISIBLE (-2700 50);
FORCEPROP 1 LAST PACK_TYPE C0805
J 0
(-2700 0);
DISPLAY 0.617021 (-2700 0);
PAINT SKYBLUE (-2700 0);
FORCEPROP 1 LAST VALUE 22UF
J 0
(-2700 250);
DISPLAY 0.617021 (-2700 250);
PAINT SKYBLUE (-2700 250);
FORCEPROP 1 LAST VOLTAGE 16V
J 0
(-2700 200);
DISPLAY 0.617021 (-2700 200);
PAINT SKYBLUE (-2700 200);
FORCEPROP 1 LAST MATERIAL X6S
J 0
(-2700 100);
DISPLAY 0.617021 (-2700 100);
PAINT SKYBLUE (-2700 100);
FORCEPROP 1 LAST TOLERANCE 20%
J 0
(-2700 150);
DISPLAY 0.617021 (-2700 150);
PAINT SKYBLUE (-2700 150);
FORCEPROP 1 LAST LOCATION PC2342
J 0
(-2700 300);
DISPLAY 0.617021 (-2700 300);
PAINT AQUA (-2700 300);
FORCEPROP 1 LASTPIN (-2750 300) $PN 1
J 0
(-2740 280);
DISPLAY 0.787234 (-2740 280);
PAINT MONO (-2740 280);
FORCEPROP 1 LASTPIN (-2750 100) $PN 2
J 0
(-2740 80);
DISPLAY 0.787234 (-2740 80);
PAINT MONO (-2740 80);
FORCEPROP 2 LAST CDS_LIB pure_quanta
J 0
(-2750 200);
DISPLAY INVISIBLE (-2750 200);
FORCEPROP 1 LAST PATH I108
J 0
(-2700 350);
DISPLAY 0.978723 (-2700 350);
PAINT WHITE (-2700 350);
DISPLAY INVISIBLE (-2700 350);
FORCEPROP 0 LAST $SEC 1
J 0
(-2700 350);
DISPLAY 0.680851 (-2700 350);
PAINT MONO (-2700 350);
DISPLAY INVISIBLE (-2700 350);
FORCEPROP 0 LAST CDS_SEC 1
J 0
(-2700 350);
DISPLAY 1.021277 (-2700 350);
DISPLAY INVISIBLE (-2700 350);
FORCEADD Q_CAP..1
(-3025 850);
FORCEPROP 1 LAST PART_NUMBER CH6223MEA01
J 0
(-2975 700);
DISPLAY 0.489362 (-2975 700);
PAINT BLUE (-2975 700);
DISPLAY INVISIBLE (-2975 700);
FORCEPROP 1 LAST PACK_TYPE C0805
J 0
(-2975 650);
DISPLAY 0.617021 (-2975 650);
PAINT SKYBLUE (-2975 650);
FORCEPROP 1 LAST VALUE 22UF
J 0
(-2975 900);
DISPLAY 0.617021 (-2975 900);
PAINT SKYBLUE (-2975 900);
FORCEPROP 1 LAST MATERIAL X6S
J 0
(-2975 750);
DISPLAY 0.617021 (-2975 750);
PAINT SKYBLUE (-2975 750);
FORCEPROP 1 LAST VOLTAGE 16V
J 0
(-2975 850);
DISPLAY 0.617021 (-2975 850);
PAINT SKYBLUE (-2975 850);
FORCEPROP 1 LAST TOLERANCE 20%
J 0
(-2975 800);
DISPLAY 0.617021 (-2975 800);
PAINT SKYBLUE (-2975 800);
FORCEPROP 1 LAST LOCATION PC570
J 0
(-2975 950);
DISPLAY 0.617021 (-2975 950);
PAINT AQUA (-2975 950);
FORCEPROP 1 LASTPIN (-3025 950) $PN 1
J 0
(-3015 930);
DISPLAY 0.617021 (-3015 930);
PAINT MONO (-3015 930);
FORCEPROP 1 LASTPIN (-3025 750) $PN 2
J 0
(-3015 730);
DISPLAY 0.617021 (-3015 730);
PAINT MONO (-3015 730);
FORCEPROP 2 LAST CDS_LIB pure_quanta
J 0
(-3025 850);
DISPLAY INVISIBLE (-3025 850);
FORCEPROP 1 LAST PATH I109
J 0
(-2975 1000);
DISPLAY 0.978723 (-2975 1000);
PAINT WHITE (-2975 1000);
DISPLAY INVISIBLE (-2975 1000);
FORCEPROP 0 LAST $SEC 1
J 0
(-2975 1000);
DISPLAY 0.680851 (-2975 1000);
PAINT MONO (-2975 1000);
DISPLAY INVISIBLE (-2975 1000);
FORCEPROP 0 LAST CDS_SEC 1
J 0
(-2975 1000);
DISPLAY 1.021277 (-2975 1000);
DISPLAY INVISIBLE (-2975 1000);
FORCEADD Q_CAP..1
(-2700 850);
FORCEPROP 1 LAST PART_NUMBER CH6223MEA01
J 0
(-2650 700);
DISPLAY 0.489362 (-2650 700);
PAINT BLUE (-2650 700);
DISPLAY INVISIBLE (-2650 700);
FORCEPROP 1 LAST VALUE 22UF
J 0
(-2650 900);
DISPLAY 0.617021 (-2650 900);
PAINT SKYBLUE (-2650 900);
FORCEPROP 1 LAST MATERIAL X6S
J 0
(-2650 750);
DISPLAY 0.617021 (-2650 750);
PAINT SKYBLUE (-2650 750);
FORCEPROP 1 LAST VOLTAGE 16V
J 0
(-2650 850);
DISPLAY 0.617021 (-2650 850);
PAINT SKYBLUE (-2650 850);
FORCEPROP 1 LAST TOLERANCE 20%
J 0
(-2650 800);
DISPLAY 0.617021 (-2650 800);
PAINT SKYBLUE (-2650 800);
FORCEPROP 1 LAST PACK_TYPE C0805
J 0
(-2650 650);
DISPLAY 0.617021 (-2650 650);
PAINT SKYBLUE (-2650 650);
FORCEPROP 1 LAST LOCATION PC571
J 0
(-2650 950);
DISPLAY 0.617021 (-2650 950);
PAINT AQUA (-2650 950);
FORCEPROP 1 LASTPIN (-2700 950) $PN 1
J 0
(-2690 930);
DISPLAY 0.617021 (-2690 930);
PAINT MONO (-2690 930);
FORCEPROP 1 LASTPIN (-2700 750) $PN 2
J 0
(-2690 730);
DISPLAY 0.617021 (-2690 730);
PAINT MONO (-2690 730);
FORCEPROP 2 LAST CDS_LIB pure_quanta
J 0
(-2700 850);
DISPLAY INVISIBLE (-2700 850);
FORCEPROP 1 LAST PATH I110
J 0
(-2650 1000);
DISPLAY 0.978723 (-2650 1000);
PAINT WHITE (-2650 1000);
DISPLAY INVISIBLE (-2650 1000);
FORCEPROP 0 LAST $SEC 1
J 0
(-2650 1000);
DISPLAY 0.680851 (-2650 1000);
PAINT MONO (-2650 1000);
DISPLAY INVISIBLE (-2650 1000);
FORCEPROP 0 LAST CDS_SEC 1
J 0
(-2650 1000);
DISPLAY 1.021277 (-2650 1000);
DISPLAY INVISIBLE (-2650 1000);
FORCEADD Q_CAP..1
(-2425 200);
FORCEPROP 1 LAST PART_NUMBER CH6223MEA01
J 0
(-2375 50);
DISPLAY 0.489362 (-2375 50);
PAINT BLUE (-2375 50);
DISPLAY INVISIBLE (-2375 50);
FORCEPROP 1 LAST PACK_TYPE C0805
J 0
(-2375 0);
DISPLAY 0.617021 (-2375 0);
PAINT SKYBLUE (-2375 0);
FORCEPROP 1 LAST VOLTAGE 16V
J 0
(-2375 200);
DISPLAY 0.617021 (-2375 200);
PAINT SKYBLUE (-2375 200);
FORCEPROP 1 LAST VALUE 22UF
J 0
(-2375 250);
DISPLAY 0.617021 (-2375 250);
PAINT SKYBLUE (-2375 250);
FORCEPROP 1 LAST TOLERANCE 20%
J 0
(-2375 150);
DISPLAY 0.617021 (-2375 150);
PAINT SKYBLUE (-2375 150);
FORCEPROP 1 LAST MATERIAL X6S
J 0
(-2375 100);
DISPLAY 0.617021 (-2375 100);
PAINT SKYBLUE (-2375 100);
FORCEPROP 1 LAST LOCATION PC2343
J 0
(-2375 300);
DISPLAY 0.617021 (-2375 300);
PAINT AQUA (-2375 300);
FORCEPROP 1 LASTPIN (-2425 300) $PN 1
J 0
(-2415 280);
DISPLAY 0.787234 (-2415 280);
PAINT MONO (-2415 280);
FORCEPROP 1 LASTPIN (-2425 100) $PN 2
J 0
(-2415 80);
DISPLAY 0.787234 (-2415 80);
PAINT MONO (-2415 80);
FORCEPROP 2 LAST CDS_LIB pure_quanta
J 0
(-2425 200);
DISPLAY INVISIBLE (-2425 200);
FORCEPROP 1 LAST PATH I111
J 0
(-2375 350);
DISPLAY 0.978723 (-2375 350);
PAINT WHITE (-2375 350);
DISPLAY INVISIBLE (-2375 350);
FORCEPROP 0 LAST $SEC 1
J 0
(-2375 350);
DISPLAY 0.680851 (-2375 350);
PAINT MONO (-2375 350);
DISPLAY INVISIBLE (-2375 350);
FORCEPROP 0 LAST CDS_SEC 1
J 0
(-2375 350);
DISPLAY 1.021277 (-2375 350);
DISPLAY INVISIBLE (-2375 350);
FORCEADD Q_CAP..1
(-2100 200);
FORCEPROP 1 LAST PART_NUMBER CH6223MEA01
J 0
(-2050 50);
DISPLAY 0.489362 (-2050 50);
PAINT BLUE (-2050 50);
DISPLAY INVISIBLE (-2050 50);
FORCEPROP 1 LAST PACK_TYPE C0805
J 0
(-2050 0);
DISPLAY 0.617021 (-2050 0);
PAINT SKYBLUE (-2050 0);
FORCEPROP 1 LAST TOLERANCE 20%
J 0
(-2050 150);
DISPLAY 0.617021 (-2050 150);
PAINT SKYBLUE (-2050 150);
FORCEPROP 1 LAST MATERIAL X6S
J 0
(-2050 100);
DISPLAY 0.617021 (-2050 100);
PAINT SKYBLUE (-2050 100);
FORCEPROP 1 LAST VOLTAGE 16V
J 0
(-2050 200);
DISPLAY 0.617021 (-2050 200);
PAINT SKYBLUE (-2050 200);
FORCEPROP 1 LAST VALUE 22UF
J 0
(-2050 250);
DISPLAY 0.617021 (-2050 250);
PAINT SKYBLUE (-2050 250);
FORCEPROP 1 LAST LOCATION PC2344
J 0
(-2050 300);
DISPLAY 0.617021 (-2050 300);
PAINT AQUA (-2050 300);
FORCEPROP 1 LASTPIN (-2100 300) $PN 1
J 0
(-2090 280);
DISPLAY 0.787234 (-2090 280);
PAINT MONO (-2090 280);
FORCEPROP 1 LASTPIN (-2100 100) $PN 2
J 0
(-2090 80);
DISPLAY 0.787234 (-2090 80);
PAINT MONO (-2090 80);
FORCEPROP 2 LAST CDS_LIB pure_quanta
J 0
(-2100 200);
DISPLAY INVISIBLE (-2100 200);
FORCEPROP 1 LAST PATH I112
J 0
(-2050 350);
DISPLAY 0.978723 (-2050 350);
PAINT WHITE (-2050 350);
DISPLAY INVISIBLE (-2050 350);
FORCEPROP 0 LAST $SEC 1
J 0
(-2050 350);
DISPLAY 0.680851 (-2050 350);
PAINT MONO (-2050 350);
DISPLAY INVISIBLE (-2050 350);
FORCEPROP 0 LAST CDS_SEC 1
J 0
(-2050 350);
DISPLAY 1.021277 (-2050 350);
DISPLAY INVISIBLE (-2050 350);
FORCEADD Q_CAP..1
(-2375 850);
FORCEPROP 1 LAST PART_NUMBER CH6223MEA01
J 0
(-2325 700);
DISPLAY 0.489362 (-2325 700);
PAINT BLUE (-2325 700);
DISPLAY INVISIBLE (-2325 700);
FORCEPROP 1 LAST MATERIAL X6S
J 0
(-2325 750);
DISPLAY 0.617021 (-2325 750);
PAINT SKYBLUE (-2325 750);
FORCEPROP 1 LAST PACK_TYPE C0805
J 0
(-2325 650);
DISPLAY 0.617021 (-2325 650);
PAINT SKYBLUE (-2325 650);
FORCEPROP 1 LAST VOLTAGE 16V
J 0
(-2325 850);
DISPLAY 0.617021 (-2325 850);
PAINT SKYBLUE (-2325 850);
FORCEPROP 1 LAST VALUE 22UF
J 0
(-2325 900);
DISPLAY 0.617021 (-2325 900);
PAINT SKYBLUE (-2325 900);
FORCEPROP 1 LAST TOLERANCE 20%
J 0
(-2325 800);
DISPLAY 0.617021 (-2325 800);
PAINT SKYBLUE (-2325 800);
FORCEPROP 1 LAST LOCATION PC576
J 0
(-2325 950);
DISPLAY 0.617021 (-2325 950);
PAINT AQUA (-2325 950);
FORCEPROP 1 LASTPIN (-2375 950) $PN 1
J 0
(-2365 930);
DISPLAY 0.617021 (-2365 930);
PAINT MONO (-2365 930);
FORCEPROP 1 LASTPIN (-2375 750) $PN 2
J 0
(-2365 730);
DISPLAY 0.617021 (-2365 730);
PAINT MONO (-2365 730);
FORCEPROP 2 LAST CDS_LIB pure_quanta
J 0
(-2375 850);
DISPLAY INVISIBLE (-2375 850);
FORCEPROP 1 LAST PATH I113
J 0
(-2325 1000);
DISPLAY 0.978723 (-2325 1000);
PAINT WHITE (-2325 1000);
DISPLAY INVISIBLE (-2325 1000);
FORCEPROP 0 LAST $SEC 1
J 0
(-2325 1000);
DISPLAY 0.680851 (-2325 1000);
PAINT MONO (-2325 1000);
DISPLAY INVISIBLE (-2325 1000);
FORCEPROP 0 LAST CDS_SEC 1
J 0
(-2325 1000);
DISPLAY 1.021277 (-2325 1000);
DISPLAY INVISIBLE (-2325 1000);
FORCEADD Q_CAP..1
(-2050 850);
FORCEPROP 1 LAST PART_NUMBER CH6223MEA01
J 0
(-2000 700);
DISPLAY 0.489362 (-2000 700);
PAINT BLUE (-2000 700);
DISPLAY INVISIBLE (-2000 700);
FORCEPROP 1 LAST TOLERANCE 20%
J 0
(-2000 800);
DISPLAY 0.617021 (-2000 800);
PAINT SKYBLUE (-2000 800);
FORCEPROP 1 LAST MATERIAL X6S
J 0
(-2000 750);
DISPLAY 0.617021 (-2000 750);
PAINT SKYBLUE (-2000 750);
FORCEPROP 1 LAST VALUE 22UF
J 0
(-2000 900);
DISPLAY 0.617021 (-2000 900);
PAINT SKYBLUE (-2000 900);
FORCEPROP 1 LAST PACK_TYPE C0805
J 0
(-2000 650);
DISPLAY 0.617021 (-2000 650);
PAINT SKYBLUE (-2000 650);
FORCEPROP 1 LAST VOLTAGE 16V
J 0
(-2000 850);
DISPLAY 0.617021 (-2000 850);
PAINT SKYBLUE (-2000 850);
FORCEPROP 1 LAST LOCATION PC71
J 0
(-2000 950);
DISPLAY 0.617021 (-2000 950);
PAINT AQUA (-2000 950);
FORCEPROP 1 LASTPIN (-2050 950) $PN 1
J 0
(-2040 930);
DISPLAY 0.617021 (-2040 930);
PAINT MONO (-2040 930);
FORCEPROP 1 LASTPIN (-2050 750) $PN 2
J 0
(-2040 730);
DISPLAY 0.617021 (-2040 730);
PAINT MONO (-2040 730);
FORCEPROP 2 LAST CDS_LIB pure_quanta
J 0
(-2050 850);
DISPLAY INVISIBLE (-2050 850);
FORCEPROP 1 LAST PATH I114
J 0
(-2000 1000);
DISPLAY 0.978723 (-2000 1000);
PAINT WHITE (-2000 1000);
DISPLAY INVISIBLE (-2000 1000);
FORCEPROP 0 LAST $SEC 1
J 0
(-2000 1000);
DISPLAY 0.680851 (-2000 1000);
PAINT MONO (-2000 1000);
DISPLAY INVISIBLE (-2000 1000);
FORCEPROP 0 LAST CDS_SEC 1
J 0
(-2000 1000);
DISPLAY 1.021277 (-2000 1000);
DISPLAY INVISIBLE (-2000 1000);
FORCEADD Q_CAP..1
(-1725 850);
FORCEPROP 1 LAST PART_NUMBER CH4104K1B00
J 0
(-1675 700);
DISPLAY 0.489362 (-1675 700);
PAINT BLUE (-1675 700);
DISPLAY INVISIBLE (-1675 700);
FORCEPROP 1 LAST VALUE 0.1UF
J 0
(-1675 900);
DISPLAY 0.617021 (-1675 900);
PAINT SKYBLUE (-1675 900);
FORCEPROP 1 LAST VOLTAGE 25V
J 0
(-1675 850);
DISPLAY 0.617021 (-1675 850);
PAINT SKYBLUE (-1675 850);
FORCEPROP 1 LAST TOLERANCE 10%
J 0
(-1675 800);
DISPLAY 0.617021 (-1675 800);
PAINT SKYBLUE (-1675 800);
FORCEPROP 1 LAST MATERIAL X7R
J 0
(-1675 750);
DISPLAY 0.617021 (-1675 750);
PAINT SKYBLUE (-1675 750);
FORCEPROP 1 LAST PACK_TYPE 0402
J 0
(-1675 650);
DISPLAY 0.617021 (-1675 650);
PAINT SKYBLUE (-1675 650);
FORCEPROP 1 LAST LOCATION PC577
J 0
(-1675 950);
DISPLAY 0.617021 (-1675 950);
PAINT AQUA (-1675 950);
FORCEPROP 1 LASTPIN (-1725 950) $PN 1
J 0
(-1715 930);
DISPLAY 0.617021 (-1715 930);
PAINT MONO (-1715 930);
FORCEPROP 1 LASTPIN (-1725 750) $PN 2
J 0
(-1715 730);
DISPLAY 0.617021 (-1715 730);
PAINT MONO (-1715 730);
FORCEPROP 2 LAST CDS_LIB pure_quanta
J 0
(-1725 850);
DISPLAY INVISIBLE (-1725 850);
FORCEPROP 1 LAST PATH I115
J 0
(-1675 1000);
DISPLAY 0.978723 (-1675 1000);
PAINT WHITE (-1675 1000);
DISPLAY INVISIBLE (-1675 1000);
FORCEPROP 0 LAST $SEC 1
J 0
(-1675 1000);
DISPLAY 0.680851 (-1675 1000);
PAINT MONO (-1675 1000);
DISPLAY INVISIBLE (-1675 1000);
FORCEPROP 0 LAST CDS_SEC 1
J 0
(-1675 1000);
DISPLAY 1.021277 (-1675 1000);
DISPLAY INVISIBLE (-1675 1000);
FORCEADD UNIVERSAL_POWER..1
(-1150 800);
FORCEPROP 3 LASTPIN (-1150 750) SIG_NAME P12V_AUX\g
J 0
(-1140 760);
DISPLAY 0.659574 (-1140 760);
PAINT MONO (-1140 760);
DISPLAY INVISIBLE (-1140 760);
FORCEPROP 1 LAST HDL_POWER P12V_AUX
J 1
(-1150 850);
DISPLAY 0.617021 (-1150 850);
PAINT GREEN (-1150 850);
FORCEPROP 2 LAST CDS_LIB logical_power
J 0
(-1150 800);
DISPLAY INVISIBLE (-1150 800);
FORCEPROP 1 LAST PATH I116
J 0
(-1100 825);
DISPLAY 0.872340 (-1100 825);
PAINT AQUA (-1100 825);
DISPLAY INVISIBLE (-1100 825);
FORCEADD GND..1
(-900 200);
FORCEPROP 3 LASTPIN (-900 250) SIG_NAME GND\g
J 0
(-890 260);
DISPLAY 0.659574 (-890 260);
PAINT MONO (-890 260);
DISPLAY INVISIBLE (-890 260);
FORCEPROP 1 LAST HDL_POWER GND
J 0
(-900 350);
DISPLAY 0.872340 (-900 350);
PAINT GREEN (-900 350);
DISPLAY INVISIBLE (-900 350);
FORCEPROP 1 LAST SIZE 1B
J 0
(-825 150);
DISPLAY 0.872340 (-825 150);
PAINT AQUA (-825 150);
DISPLAY INVISIBLE (-825 150);
FORCEPROP 2 LAST CDS_LIB logical_power
J 0
(-900 200);
DISPLAY INVISIBLE (-900 200);
FORCEPROP 1 LAST PATH I117
J 0
(-825 200);
DISPLAY 0.872340 (-825 200);
PAINT AQUA (-825 200);
DISPLAY INVISIBLE (-825 200);
FORCEADD Q_CAP..1
(-900 475);
FORCEPROP 1 LAST PART_NUMBER CH5473KE902
J 0
(-850 325);
DISPLAY 0.489362 (-850 325);
PAINT BLUE (-850 325);
DISPLAY INVISIBLE (-850 325);
FORCEPROP 1 LAST VOLTAGE 16V
J 0
(-850 475);
DISPLAY 0.617021 (-850 475);
PAINT SKYBLUE (-850 475);
FORCEPROP 1 LAST PACK_TYPE C0603
J 0
(-850 275);
DISPLAY 0.617021 (-850 275);
PAINT SKYBLUE (-850 275);
FORCEPROP 1 LAST MATERIAL X6S
J 0
(-850 375);
DISPLAY 0.617021 (-850 375);
PAINT SKYBLUE (-850 375);
FORCEPROP 1 LAST VALUE 4.7UF
J 0
(-850 525);
DISPLAY 0.617021 (-850 525);
PAINT SKYBLUE (-850 525);
FORCEPROP 1 LAST TOLERANCE 10%
J 0
(-850 425);
DISPLAY 0.617021 (-850 425);
PAINT SKYBLUE (-850 425);
FORCEPROP 1 LAST LOCATION PC8
J 0
(-850 575);
DISPLAY 0.617021 (-850 575);
PAINT AQUA (-850 575);
FORCEPROP 1 LASTPIN (-900 575) $PN 1
J 0
(-890 555);
DISPLAY 0.787234 (-890 555);
PAINT MONO (-890 555);
FORCEPROP 1 LASTPIN (-900 375) $PN 2
J 0
(-890 355);
DISPLAY 0.787234 (-890 355);
PAINT MONO (-890 355);
FORCEPROP 2 LAST CDS_LIB pure_quanta
J 0
(-900 475);
DISPLAY INVISIBLE (-900 475);
FORCEPROP 1 LAST PATH I118
J 0
(-850 625);
DISPLAY 0.978723 (-850 625);
PAINT WHITE (-850 625);
DISPLAY INVISIBLE (-850 625);
FORCEPROP 0 LAST $SEC 1
J 0
(-850 625);
DISPLAY 0.680851 (-850 625);
PAINT MONO (-850 625);
DISPLAY INVISIBLE (-850 625);
FORCEPROP 0 LAST CDS_SEC 1
J 0
(-850 625);
DISPLAY 1.021277 (-850 625);
DISPLAY INVISIBLE (-850 625);
FORCEADD GND..1
(350 -1500);
FORCEPROP 3 LASTPIN (350 -1450) SIG_NAME GND\g
J 0
(360 -1440);
DISPLAY 0.659574 (360 -1440);
PAINT MONO (360 -1440);
DISPLAY INVISIBLE (360 -1440);
FORCEPROP 1 LAST HDL_POWER GND
J 0
(350 -1350);
DISPLAY 0.872340 (350 -1350);
PAINT GREEN (350 -1350);
DISPLAY INVISIBLE (350 -1350);
FORCEPROP 2 LAST CDS_LIB logical_power
J 0
(350 -1500);
DISPLAY INVISIBLE (350 -1500);
FORCEPROP 1 LAST SIZE 1B
J 0
(425 -1550);
DISPLAY 0.872340 (425 -1550);
PAINT AQUA (425 -1550);
DISPLAY INVISIBLE (425 -1550);
FORCEPROP 1 LAST PATH I119
J 0
(425 -1500);
DISPLAY 0.872340 (425 -1500);
PAINT AQUA (425 -1500);
DISPLAY INVISIBLE (425 -1500);
FORCEADD GND..1
R 1
(550 -1200);
FORCEPROP 3 LASTPIN (500 -1200) SIG_NAME GND\g
J 0
(510 -1190);
DISPLAY 0.659574 (510 -1190);
PAINT MONO (510 -1190);
DISPLAY INVISIBLE (510 -1190);
FORCEPROP 1 LAST HDL_POWER GND
R 1
J 0
(400 -1200);
DISPLAY 0.872340 (400 -1200);
PAINT GREEN (400 -1200);
DISPLAY INVISIBLE (400 -1200);
FORCEPROP 2 LAST CDS_LIB logical_power
R 1
J 0
(550 -1200);
DISPLAY INVISIBLE (550 -1200);
FORCEPROP 1 LAST SIZE 1B
R 1
J 0
(600 -1125);
DISPLAY 0.872340 (600 -1125);
PAINT AQUA (600 -1125);
DISPLAY INVISIBLE (600 -1125);
FORCEPROP 1 LAST PATH I120
R 1
J 0
(550 -1125);
DISPLAY 0.872340 (550 -1125);
PAINT AQUA (550 -1125);
DISPLAY INVISIBLE (550 -1125);
FORCEADD Q_RES..1
(825 -1250);
FORCEPROP 1 LAST PART_NUMBER CS21002FB06
J 0
(675 -1475);
DISPLAY 0.617021 (675 -1475);
PAINT BLUE (675 -1475);
DISPLAY INVISIBLE (675 -1475);
FORCEPROP 1 LAST MATERIAL EMPTY
J 0
(825 -1400);
DISPLAY 0.617021 (825 -1400);
PAINT RED (825 -1400);
FORCEPROP 1 LAST WATTAGE 1/16W
J 2
(800 -1400);
DISPLAY 0.617021 (800 -1400);
PAINT SKYBLUE (800 -1400);
FORCEPROP 1 LAST VALUE 1K
J 2
(800 -1350);
DISPLAY 0.617021 (800 -1350);
PAINT SKYBLUE (800 -1350);
FORCEPROP 1 LAST PACK_TYPE 0402LF
J 0
(900 -1350);
DISPLAY 0.617021 (900 -1350);
PAINT SKYBLUE (900 -1350);
FORCEPROP 1 LAST TOLERANCE 1%
J 0
(825 -1350);
DISPLAY 0.617021 (825 -1350);
PAINT SKYBLUE (825 -1350);
FORCEPROP 1 LAST LOCATION PR836
J 0
(775 -1200);
DISPLAY 0.617021 (775 -1200);
PAINT AQUA (775 -1200);
FORCEPROP 1 LASTPIN (725 -1250) $PN 1
J 0
(737 -1238);
DISPLAY 0.617021 (737 -1238);
PAINT MONO (737 -1238);
FORCEPROP 1 LASTPIN (925 -1250) $PN 2
J 0
(887 -1238);
DISPLAY 0.617021 (887 -1238);
PAINT MONO (887 -1238);
FORCEPROP 2 LAST CDS_LIB pure_quanta
J 0
(825 -1250);
DISPLAY INVISIBLE (825 -1250);
FORCEPROP 1 LAST PATH I121
J 0
(775 -1100);
DISPLAY 0.978723 (775 -1100);
PAINT WHITE (775 -1100);
DISPLAY INVISIBLE (775 -1100);
FORCEPROP 0 LAST $SEC 1
J 0
(775 -1150);
DISPLAY 0.680851 (775 -1150);
PAINT MONO (775 -1150);
DISPLAY INVISIBLE (775 -1150);
FORCEPROP 0 LAST CDS_SEC 1
J 0
(775 -1150);
DISPLAY 1.021277 (775 -1150);
DISPLAY INVISIBLE (775 -1150);
FORCEADD Q_CAP..2
(725 -550);
FORCEPROP 1 LAST PART_NUMBER CH4224K1B01
J 1
(800 -675);
DISPLAY 0.617021 (800 -675);
PAINT BLUE (800 -675);
DISPLAY INVISIBLE (800 -675);
FORCEPROP 1 LAST VOLTAGE 25V
J 0
(975 -600);
DISPLAY 0.617021 (975 -600);
PAINT SKYBLUE (975 -600);
FORCEPROP 1 LAST MATERIAL X7R
J 0
(975 -650);
DISPLAY 0.617021 (975 -650);
PAINT SKYBLUE (975 -650);
FORCEPROP 1 LAST TOLERANCE 10%
J 2
(975 -650);
DISPLAY 0.617021 (975 -650);
PAINT SKYBLUE (975 -650);
FORCEPROP 1 LAST VALUE 0.22UF
J 2
(975 -600);
DISPLAY 0.617021 (975 -600);
PAINT SKYBLUE (975 -600);
FORCEPROP 1 LAST LOCATION PC568
J 1
(725 -625);
DISPLAY 0.617021 (725 -625);
PAINT AQUA (725 -625);
FORCEPROP 1 LASTPIN (625 -550) $PN 1
J 0
(615 -535);
DISPLAY 0.617021 (615 -535);
PAINT MONO (615 -535);
FORCEPROP 1 LASTPIN (825 -550) $PN 2
J 0
(810 -535);
DISPLAY 0.617021 (810 -535);
PAINT MONO (810 -535);
FORCEPROP 2 LAST CDS_LIB pure_quanta
J 0
(725 -550);
DISPLAY INVISIBLE (725 -550);
FORCEPROP 1 LAST PACK_TYPE C0402
J 1
(975 -700);
DISPLAY 0.617021 (975 -700);
PAINT SKYBLUE (975 -700);
DISPLAY INVISIBLE (975 -700);
FORCEPROP 1 LAST PATH I122
J 0
(725 -350);
DISPLAY 0.978723 (725 -350);
PAINT WHITE (725 -350);
DISPLAY INVISIBLE (725 -350);
FORCEPROP 0 LAST $SEC 1
J 0
(975 -550);
DISPLAY 0.680851 (975 -550);
PAINT MONO (975 -550);
DISPLAY INVISIBLE (975 -550);
FORCEPROP 2 LAST CDS_SEC 1
J 0
(725 -300);
DISPLAY 1.021277 (725 -300);
DISPLAY INVISIBLE (725 -300);
FORCEADD Q_RES..1
(800 -350);
FORCEPROP 1 LAST PART_NUMBER CS00002JB13
J 0
(500 -400);
DISPLAY 0.617021 (500 -400);
PAINT BLUE (500 -400);
DISPLAY INVISIBLE (500 -400);
FORCEPROP 1 LAST WATTAGE 1/16W
J 2
(750 -450);
DISPLAY 0.617021 (750 -450);
PAINT SKYBLUE (750 -450);
FORCEPROP 1 LAST PACK_TYPE 0402LF
J 0
(850 -400);
DISPLAY 0.617021 (850 -400);
PAINT SKYBLUE (850 -400);
FORCEPROP 1 LAST TOLERANCE 5%
J 0
(775 -400);
DISPLAY 0.617021 (775 -400);
PAINT SKYBLUE (775 -400);
FORCEPROP 1 LAST VALUE 0
J 2
(750 -400);
DISPLAY 0.617021 (750 -400);
PAINT SKYBLUE (750 -400);
FORCEPROP 1 LAST MATERIAL CHIP
J 0
(775 -450);
DISPLAY 0.617021 (775 -450);
PAINT SKYBLUE (775 -450);
FORCEPROP 1 LAST LOCATION PR835
J 0
(575 -350);
DISPLAY 0.617021 (575 -350);
PAINT AQUA (575 -350);
FORCEPROP 1 LASTPIN (700 -350) $PN 1
J 0
(712 -338);
DISPLAY 0.617021 (712 -338);
PAINT MONO (712 -338);
FORCEPROP 1 LASTPIN (900 -350) $PN 2
J 0
(862 -338);
DISPLAY 0.617021 (862 -338);
PAINT MONO (862 -338);
FORCEPROP 2 LAST CDS_LIB pure_quanta
J 0
(800 -350);
DISPLAY INVISIBLE (800 -350);
FORCEPROP 1 LAST PATH I123
J 0
(750 -200);
DISPLAY 0.978723 (750 -200);
PAINT WHITE (750 -200);
DISPLAY INVISIBLE (750 -200);
FORCEPROP 0 LAST $SEC 1
J 0
(850 -350);
DISPLAY 0.680851 (850 -350);
PAINT MONO (850 -350);
DISPLAY INVISIBLE (850 -350);
FORCEPROP 0 LAST CDS_SEC 1
J 0
(850 -350);
DISPLAY 1.021277 (850 -350);
DISPLAY INVISIBLE (850 -350);
FORCEADD GND..1
(1200 -2000);
FORCEPROP 3 LASTPIN (1200 -1950) SIG_NAME GND\g
J 0
(1210 -1940);
DISPLAY 0.659574 (1210 -1940);
PAINT MONO (1210 -1940);
DISPLAY INVISIBLE (1210 -1940);
FORCEPROP 1 LAST HDL_POWER GND
J 0
(1200 -1850);
DISPLAY 0.872340 (1200 -1850);
PAINT GREEN (1200 -1850);
DISPLAY INVISIBLE (1200 -1850);
FORCEPROP 1 LAST SIZE 1B
J 0
(1275 -2050);
DISPLAY 0.872340 (1275 -2050);
PAINT AQUA (1275 -2050);
DISPLAY INVISIBLE (1275 -2050);
FORCEPROP 2 LAST CDS_LIB logical_power
J 0
(1200 -2000);
PAINT MONO (1200 -2000);
DISPLAY INVISIBLE (1200 -2000);
FORCEPROP 1 LAST PATH I124
J 0
(1275 -2000);
DISPLAY 0.872340 (1275 -2000);
PAINT AQUA (1275 -2000);
DISPLAY INVISIBLE (1275 -2000);
FORCEADD Q_RES..2
(1200 -1725);
FORCEPROP 1 LAST PART_NUMBER CS31502BB03
J 0
(1245 -1850);
DISPLAY 0.489362 (1245 -1850);
PAINT BLUE (1245 -1850);
DISPLAY INVISIBLE (1245 -1850);
FORCEPROP 1 LAST TOLERANCE 0.1%
J 0
(1250 -1700);
DISPLAY 0.489362 (1250 -1700);
PAINT SKYBLUE (1250 -1700);
FORCEPROP 1 LAST VALUE 15K
J 0
(1250 -1650);
DISPLAY 0.489362 (1250 -1650);
PAINT SKYBLUE (1250 -1650);
FORCEPROP 1 LAST PACK_TYPE 0402LF
J 0
(1245 -1900);
DISPLAY 0.489362 (1245 -1900);
PAINT SKYBLUE (1245 -1900);
FORCEPROP 1 LAST WATTAGE 1/16W
J 0
(1245 -1750);
DISPLAY 0.489362 (1245 -1750);
PAINT SKYBLUE (1245 -1750);
FORCEPROP 1 LAST MATERIAL CHIP
J 0
(1245 -1800);
DISPLAY 0.489362 (1245 -1800);
PAINT SKYBLUE (1245 -1800);
FORCEPROP 1 LAST LOCATION PR830
J 0
(1250 -1600);
DISPLAY 0.617021 (1250 -1600);
PAINT AQUA (1250 -1600);
FORCEPROP 1 LASTPIN (1200 -1625) $PN 1
J 0
(1205 -1663);
DISPLAY 0.617021 (1205 -1663);
PAINT MONO (1205 -1663);
FORCEPROP 1 LASTPIN (1200 -1825) $PN 2
J 0
(1205 -1815);
DISPLAY 0.617021 (1205 -1815);
PAINT MONO (1205 -1815);
FORCEPROP 2 LAST CDS_LIB pure_quanta
J 0
(1200 -1725);
DISPLAY INVISIBLE (1200 -1725);
FORCEPROP 1 LAST PATH I125
J 0
(1250 -1550);
DISPLAY 0.978723 (1250 -1550);
PAINT WHITE (1250 -1550);
DISPLAY INVISIBLE (1250 -1550);
FORCEPROP 0 LAST $SEC 1
J 0
(1250 -1550);
DISPLAY 0.680851 (1250 -1550);
PAINT MONO (1250 -1550);
DISPLAY INVISIBLE (1250 -1550);
FORCEPROP 2 LAST CDS_SEC 1
J 0
(1250 -1500);
DISPLAY 1.021277 (1250 -1500);
DISPLAY INVISIBLE (1250 -1500);
FORCEADD UNIVERSAL_POWER..1
(1075 -1150);
FORCEPROP 3 LASTPIN (1075 -1200) SIG_NAME P3V3_AUX\g
J 0
(1085 -1190);
DISPLAY 0.659574 (1085 -1190);
PAINT MONO (1085 -1190);
DISPLAY INVISIBLE (1085 -1190);
FORCEPROP 1 LAST HDL_POWER P3V3_AUX
J 1
(1075 -1100);
DISPLAY 0.617021 (1075 -1100);
PAINT GREEN (1075 -1100);
FORCEPROP 2 LAST CDS_LIB logical_power
J 0
(1075 -1150);
DISPLAY INVISIBLE (1075 -1150);
FORCEPROP 1 LAST PATH I126
J 0
(1125 -1125);
DISPLAY 0.872340 (1125 -1125);
PAINT AQUA (1125 -1125);
DISPLAY INVISIBLE (1125 -1125);
FORCEADD Q_CAP..2
(2100 -1850);
FORCEPROP 1 LAST PART_NUMBER TMP_QCH12206KB14
J 1
(2175 -2000);
DISPLAY 0.617021 (2175 -2000);
PAINT BLUE (2175 -2000);
DISPLAY INVISIBLE (2175 -2000);
FORCEPROP 1 LAST PACK_TYPE 0402
J 1
(2075 -1950);
DISPLAY 0.617021 (2075 -1950);
PAINT SKYBLUE (2075 -1950);
FORCEPROP 1 LAST VALUE 220PF
J 2
(2275 -1900);
DISPLAY 0.617021 (2275 -1900);
PAINT SKYBLUE (2275 -1900);
FORCEPROP 1 LAST TOLERANCE 10%
J 2
(2375 -1900);
DISPLAY 0.617021 (2375 -1900);
PAINT SKYBLUE (2375 -1900);
FORCEPROP 1 LAST MATERIAL X7R
J 0
(2400 -1900);
DISPLAY 0.617021 (2400 -1900);
PAINT SKYBLUE (2400 -1900);
FORCEPROP 1 LAST VOLTAGE 50V
J 0
(2175 -1950);
DISPLAY 0.617021 (2175 -1950);
PAINT SKYBLUE (2175 -1950);
FORCEPROP 1 LAST LOCATION PC569
J 1
(1925 -1850);
DISPLAY 0.765957 (1925 -1850);
PAINT AQUA (1925 -1850);
FORCEPROP 1 LASTPIN (2000 -1850) $PN 1
J 0
(1990 -1835);
DISPLAY 0.787234 (1990 -1835);
PAINT MONO (1990 -1835);
FORCEPROP 1 LASTPIN (2200 -1850) $PN 2
J 0
(2185 -1835);
DISPLAY 0.787234 (2185 -1835);
PAINT MONO (2185 -1835);
FORCEPROP 2 LAST CDS_LIB pure_quanta
J 0
(2100 -1850);
DISPLAY INVISIBLE (2100 -1850);
FORCEPROP 1 LAST PATH I127
J 0
(2100 -1650);
DISPLAY 0.978723 (2100 -1650);
PAINT WHITE (2100 -1650);
DISPLAY INVISIBLE (2100 -1650);
FORCEPROP 0 LAST $SEC 1
J 0
(1925 -1800);
DISPLAY 0.680851 (1925 -1800);
PAINT MONO (1925 -1800);
DISPLAY INVISIBLE (1925 -1800);
FORCEPROP 0 LAST CDS_SEC 1
J 0
(1925 -1800);
DISPLAY 1.021277 (1925 -1800);
DISPLAY INVISIBLE (1925 -1800);
FORCEADD Q_RES..1
(2100 -1550);
FORCEPROP 1 LAST PART_NUMBER CS34702BB05
J 0
(2225 -1525);
DISPLAY 0.638298 (2225 -1525);
DISPLAY INVISIBLE (2225 -1525);
FORCEPROP 1 LAST PACK_TYPE 0402LF
J 0
(2325 -1625);
DISPLAY 0.638298 (2325 -1625);
FORCEPROP 1 LAST WATTAGE 1/16W
J 2
(2075 -1675);
DISPLAY 0.638298 (2075 -1675);
FORCEPROP 1 LAST VALUE 47K
J 2
(2075 -1625);
DISPLAY 0.638298 (2075 -1625);
FORCEPROP 1 LAST MATERIAL CHIP
J 0
(2100 -1675);
DISPLAY 0.638298 (2100 -1675);
FORCEPROP 1 LAST TOLERANCE 0.1%
J 0
(2100 -1625);
DISPLAY 0.638298 (2100 -1625);
FORCEPROP 1 LAST LOCATION PR831
J 0
(2050 -1500);
DISPLAY 0.638298 (2050 -1500);
FORCEPROP 2 LAST CDS_LIB pure_quanta
J 0
(2100 -1550);
DISPLAY INVISIBLE (2100 -1550);
FORCEPROP 1 LAST PATH I128
J 0
(2050 -1400);
DISPLAY 0.978723 (2050 -1400);
PAINT WHITE (2050 -1400);
DISPLAY INVISIBLE (2050 -1400);
FORCEPROP 0 LAST $SEC 1
J 0
(2050 -1400);
DISPLAY 0.680851 (2050 -1400);
PAINT MONO (2050 -1400);
DISPLAY INVISIBLE (2050 -1400);
FORCEPROP 2 LAST CDS_SEC 1
J 0
(2050 -1350);
DISPLAY 1.021277 (2050 -1350);
DISPLAY INVISIBLE (2050 -1350);
FORCEPROP 1 LASTPIN (2000 -1550) $PN 1
J 0
(2012 -1538);
DISPLAY 0.787234 (2012 -1538);
PAINT MONO (2012 -1538);
DISPLAY INVISIBLE (2012 -1538);
FORCEPROP 1 LASTPIN (2200 -1550) $PN 2
J 0
(2162 -1538);
DISPLAY 0.787234 (2162 -1538);
PAINT MONO (2162 -1538);
DISPLAY INVISIBLE (2162 -1538);
FORCEADD Q_INDUCTOR..1
(1425 -725);
FORCEPROP 1 LAST PART_NUMBER CV-15^0MZ02
J 0
(1300 -615);
DISPLAY 0.617021 (1300 -615);
PAINT BLUE (1300 -615);
DISPLAY INVISIBLE (1300 -615);
FORCEPROP 1 LAST MATERIAL IND
J 0
(1300 -670);
DISPLAY 0.617021 (1300 -670);
PAINT SKYBLUE (1300 -670);
FORCEPROP 2 LAST VALUE 1.5UH/53A
J 0
(1300 -525);
DISPLAY 0.617021 (1300 -525);
PAINT SKYBLUE (1300 -525);
FORCEPROP 2 LAST PACK_TYPE SMLF
J 0
(1300 -475);
DISPLAY 0.617021 (1300 -475);
PAINT SKYBLUE (1300 -475);
FORCEPROP 1 LAST LOCATION PL66
J 0
(1300 -565);
DISPLAY 0.617021 (1300 -565);
PAINT AQUA (1300 -565);
FORCEPROP 0 LASTPIN (1325 -750) $PN 1
J 2
(1315 -740);
DISPLAY 0.617021 (1315 -740);
PAINT MONO (1315 -740);
FORCEPROP 0 LASTPIN (1525 -750) $PN 2
J 0
(1535 -740);
DISPLAY 0.617021 (1535 -740);
PAINT MONO (1535 -740);
FORCEPROP 1 LAST NEEDS_NO_SIZE TRUE
J 0
(1425 -725);
DISPLAY 0.468085 (1425 -725);
PAINT GREEN (1425 -725);
DISPLAY INVISIBLE (1425 -725);
FORCEPROP 2 LAST CDS_LIB pure_quanta
J 0
(1425 -725);
DISPLAY INVISIBLE (1425 -725);
FORCEPROP 1 LAST PATH I129
J 0
(1500 -670);
DISPLAY 0.723404 (1500 -670);
PAINT GREEN (1500 -670);
DISPLAY INVISIBLE (1500 -670);
FORCEPROP 0 LAST $SEC 1
J 0
(1300 -425);
DISPLAY 0.680851 (1300 -425);
PAINT MONO (1300 -425);
DISPLAY INVISIBLE (1300 -425);
FORCEPROP 2 LAST CDS_SEC 1
J 0
(1300 -425);
DISPLAY 1.021277 (1300 -425);
DISPLAY INVISIBLE (1300 -425);
FORCEADD OFFPAGE..2
(1400 -100);
FORCEPROP 2 LAST $XR2 258 
J 0
(1829 -100);
DISPLAY 0.638298 (1829 -100);
PAINT MONO (1829 -100);
FORCEPROP 2 LAST $XR1 244 
J 0
(1709 -100);
DISPLAY 0.638298 (1709 -100);
PAINT MONO (1709 -100);
FORCEPROP 2 LAST $XR0 222 
J 0
(1589 -100);
DISPLAY 0.638298 (1589 -100);
PAINT MONO (1589 -100);
FORCEPROP 1 LAST COMMENT_BODY TRUE
J 0
(1355 -195);
DISPLAY 0.872340 (1355 -195);
PAINT GREEN (1355 -195);
DISPLAY INVISIBLE (1355 -195);
FORCEPROP 1 LAST OFFPAGE TRUE
J 0
(1725 -225);
DISPLAY 0.872340 (1725 -225);
PAINT GREEN (1725 -225);
DISPLAY INVISIBLE (1725 -225);
FORCEPROP 2 LAST CDS_LIB standard
J 0
(1400 -100);
PAINT MONO (1400 -100);
DISPLAY INVISIBLE (1400 -100);
FORCEPROP 2 LAST PATH I130
J 0
(1850 -50);
DISPLAY 1.021277 (1850 -50);
DISPLAY INVISIBLE (1850 -50);
FORCEADD Q_CAPP..1
(1650 -975);
FORCEPROP 1 LAST PART_NUMBER CC75601MD16
J 0
(1700 -1175);
DISPLAY 0.638298 (1700 -1175);
DISPLAY INVISIBLE (1700 -1175);
FORCEPROP 1 LAST VALUE 560UF
J 0
(1700 -925);
DISPLAY 0.638298 (1700 -925);
FORCEPROP 1 LAST MATERIAL OSCON
J 0
(1700 -1075);
DISPLAY 0.638298 (1700 -1075);
FORCEPROP 1 LAST VOLTAGE 6.3V
J 0
(1700 -1025);
DISPLAY 0.638298 (1700 -1025);
FORCEPROP 1 LAST TOLERANCE 20%
J 0
(1700 -975);
DISPLAY 0.638298 (1700 -975);
FORCEPROP 1 LAST PACK_TYPE THLF
J 0
(1700 -1125);
DISPLAY 0.638298 (1700 -1125);
FORCEPROP 1 LAST LOCATION PC1866
J 0
(1700 -875);
DISPLAY 0.638298 (1700 -875);
FORCEPROP 1 LASTPIN (1650 -875) $PN 1
J 0
(1660 -890);
DISPLAY 0.787234 (1660 -890);
PAINT MONO (1660 -890);
FORCEPROP 1 LASTPIN (1650 -1075) $PN 2
J 0
(1660 -1090);
DISPLAY 0.787234 (1660 -1090);
PAINT MONO (1660 -1090);
FORCEPROP 2 LAST CDS_LIB pure_quanta
J 0
(1650 -975);
DISPLAY INVISIBLE (1650 -975);
FORCEPROP 1 LAST PATH I131
J 0
(1700 -825);
DISPLAY 0.978723 (1700 -825);
DISPLAY INVISIBLE (1700 -825);
FORCEPROP 0 LAST $SEC 1
J 0
(1700 -825);
DISPLAY 0.680851 (1700 -825);
PAINT MONO (1700 -825);
DISPLAY INVISIBLE (1700 -825);
FORCEPROP 2 LAST CDS_SEC 1
J 0
(1700 -775);
DISPLAY 1.021277 (1700 -775);
DISPLAY INVISIBLE (1700 -775);
FORCEADD Q_CAPP..1
(2100 -975);
FORCEPROP 1 LAST PART_NUMBER CC75601MD16
J 0
(2150 -1175);
DISPLAY 0.638298 (2150 -1175);
DISPLAY INVISIBLE (2150 -1175);
FORCEPROP 1 LAST PACK_TYPE THLF
J 0
(2150 -1125);
DISPLAY 0.638298 (2150 -1125);
FORCEPROP 1 LAST MATERIAL OSCON
J 0
(2150 -1075);
DISPLAY 0.638298 (2150 -1075);
FORCEPROP 1 LAST VOLTAGE 6.3V
J 0
(2150 -1025);
DISPLAY 0.638298 (2150 -1025);
FORCEPROP 1 LAST TOLERANCE 20%
J 0
(2150 -975);
DISPLAY 0.638298 (2150 -975);
FORCEPROP 1 LAST VALUE 560UF
J 0
(2150 -925);
DISPLAY 0.638298 (2150 -925);
FORCEPROP 1 LAST LOCATION PC1867
J 0
(2150 -875);
DISPLAY 0.638298 (2150 -875);
FORCEPROP 1 LASTPIN (2100 -875) $PN 1
J 0
(2110 -890);
DISPLAY 0.787234 (2110 -890);
PAINT MONO (2110 -890);
FORCEPROP 1 LASTPIN (2100 -1075) $PN 2
J 0
(2110 -1090);
DISPLAY 0.787234 (2110 -1090);
PAINT MONO (2110 -1090);
FORCEPROP 2 LAST CDS_LIB pure_quanta
J 0
(2100 -975);
DISPLAY INVISIBLE (2100 -975);
FORCEPROP 1 LAST PATH I132
J 0
(2150 -825);
DISPLAY 0.978723 (2150 -825);
DISPLAY INVISIBLE (2150 -825);
FORCEPROP 0 LAST $SEC 1
J 0
(2150 -825);
DISPLAY 0.680851 (2150 -825);
PAINT MONO (2150 -825);
DISPLAY INVISIBLE (2150 -825);
FORCEPROP 0 LAST CDS_SEC 1
J 0
(2150 -825);
DISPLAY 1.021277 (2150 -825);
DISPLAY INVISIBLE (2150 -825);
FORCEADD Q_CAP..1
(2550 -950);
FORCEPROP 1 LAST PART_NUMBER CH6222MEA01
J 0
(2625 -1125);
DISPLAY 0.617021 (2625 -1125);
PAINT BLUE (2625 -1125);
DISPLAY INVISIBLE (2625 -1125);
FORCEPROP 1 LAST MATERIAL X6S
J 0
(2625 -1075);
DISPLAY 0.617021 (2625 -1075);
PAINT SKYBLUE (2625 -1075);
FORCEPROP 1 LAST VOLTAGE 10V
J 0
(2625 -975);
DISPLAY 0.617021 (2625 -975);
PAINT SKYBLUE (2625 -975);
FORCEPROP 1 LAST TOLERANCE 20%
J 0
(2625 -1025);
DISPLAY 0.617021 (2625 -1025);
PAINT SKYBLUE (2625 -1025);
FORCEPROP 1 LAST PACK_TYPE C0805
J 0
(2625 -1175);
DISPLAY 0.617021 (2625 -1175);
PAINT SKYBLUE (2625 -1175);
FORCEPROP 1 LAST VALUE 22UF
J 0
(2625 -925);
DISPLAY 0.617021 (2625 -925);
PAINT SKYBLUE (2625 -925);
FORCEPROP 1 LAST LOCATION PC1868
J 0
(2625 -875);
DISPLAY 0.617021 (2625 -875);
PAINT AQUA (2625 -875);
FORCEPROP 1 LASTPIN (2550 -850) $PN 1
J 0
(2560 -870);
DISPLAY 0.617021 (2560 -870);
PAINT MONO (2560 -870);
FORCEPROP 1 LASTPIN (2550 -1050) $PN 2
J 0
(2560 -1070);
DISPLAY 0.617021 (2560 -1070);
PAINT MONO (2560 -1070);
FORCEPROP 2 LAST CDS_LIB pure_quanta
J 0
(2550 -950);
DISPLAY INVISIBLE (2550 -950);
FORCEPROP 1 LAST PATH I133
J 0
(2600 -800);
DISPLAY 0.978723 (2600 -800);
PAINT WHITE (2600 -800);
DISPLAY INVISIBLE (2600 -800);
FORCEPROP 0 LAST $SEC 1
J 0
(2600 -800);
DISPLAY 0.680851 (2600 -800);
PAINT MONO (2600 -800);
DISPLAY INVISIBLE (2600 -800);
FORCEPROP 0 LAST CDS_SEC 1
J 0
(2600 -800);
DISPLAY 0.680851 (2600 -800);
DISPLAY INVISIBLE (2600 -800);
FORCEADD Q_CAP..1
(2950 -975);
FORCEPROP 1 LAST PART_NUMBER CH6222MEA01
J 0
(3000 -1125);
DISPLAY 0.617021 (3000 -1125);
PAINT BLUE (3000 -1125);
DISPLAY INVISIBLE (3000 -1125);
FORCEPROP 1 LAST VALUE 22UF
J 0
(3000 -925);
DISPLAY 0.617021 (3000 -925);
PAINT SKYBLUE (3000 -925);
FORCEPROP 1 LAST VOLTAGE 10V
J 0
(3000 -975);
DISPLAY 0.617021 (3000 -975);
PAINT SKYBLUE (3000 -975);
FORCEPROP 1 LAST TOLERANCE 20%
J 0
(3000 -1025);
DISPLAY 0.617021 (3000 -1025);
PAINT SKYBLUE (3000 -1025);
FORCEPROP 1 LAST MATERIAL X6S
J 0
(3000 -1075);
DISPLAY 0.617021 (3000 -1075);
PAINT SKYBLUE (3000 -1075);
FORCEPROP 1 LAST PACK_TYPE C0805
J 0
(3000 -1175);
DISPLAY 0.617021 (3000 -1175);
PAINT SKYBLUE (3000 -1175);
FORCEPROP 1 LAST LOCATION PC1599
J 0
(3000 -875);
DISPLAY 0.574468 (3000 -875);
PAINT AQUA (3000 -875);
FORCEPROP 1 LASTPIN (2950 -875) $PN 1
J 0
(2960 -895);
DISPLAY 0.617021 (2960 -895);
PAINT MONO (2960 -895);
FORCEPROP 1 LASTPIN (2950 -1075) $PN 2
J 0
(2960 -1095);
DISPLAY 0.617021 (2960 -1095);
PAINT MONO (2960 -1095);
FORCEPROP 2 LAST CDS_LIB pure_quanta
J 0
(2950 -975);
DISPLAY INVISIBLE (2950 -975);
FORCEPROP 1 LAST PATH I134
J 0
(3000 -825);
DISPLAY 0.978723 (3000 -825);
PAINT WHITE (3000 -825);
DISPLAY INVISIBLE (3000 -825);
FORCEPROP 0 LAST $SEC 1
J 0
(3000 -825);
DISPLAY 0.680851 (3000 -825);
PAINT MONO (3000 -825);
DISPLAY INVISIBLE (3000 -825);
FORCEPROP 0 LAST CDS_SEC 1
J 0
(3000 -825);
DISPLAY 1.021277 (3000 -825);
DISPLAY INVISIBLE (3000 -825);
FORCEADD GND..1
(3725 -1350);
FORCEPROP 3 LASTPIN (3725 -1300) SIG_NAME GND\g
J 0
(3735 -1290);
DISPLAY 0.659574 (3735 -1290);
PAINT MONO (3735 -1290);
DISPLAY INVISIBLE (3735 -1290);
FORCEPROP 1 LAST HDL_POWER GND
J 0
(3725 -1200);
DISPLAY 0.872340 (3725 -1200);
PAINT GREEN (3725 -1200);
DISPLAY INVISIBLE (3725 -1200);
FORCEPROP 1 LAST SIZE 1B
J 0
(3800 -1400);
DISPLAY 0.872340 (3800 -1400);
PAINT AQUA (3800 -1400);
DISPLAY INVISIBLE (3800 -1400);
FORCEPROP 2 LAST CDS_LIB logical_power
J 0
(3725 -1350);
PAINT MONO (3725 -1350);
DISPLAY INVISIBLE (3725 -1350);
FORCEPROP 1 LAST PATH I135
J 0
(3800 -1350);
DISPLAY 0.872340 (3800 -1350);
PAINT AQUA (3800 -1350);
DISPLAY INVISIBLE (3800 -1350);
FORCEADD Q_CAP..1
(3325 -975);
FORCEPROP 1 LAST PART_NUMBER CH6222MEA01
J 0
(3375 -1125);
DISPLAY 0.617021 (3375 -1125);
PAINT BLUE (3375 -1125);
DISPLAY INVISIBLE (3375 -1125);
FORCEPROP 1 LAST VOLTAGE 10V
J 0
(3375 -975);
DISPLAY 0.617021 (3375 -975);
PAINT SKYBLUE (3375 -975);
FORCEPROP 1 LAST TOLERANCE 20%
J 0
(3375 -1025);
DISPLAY 0.617021 (3375 -1025);
PAINT SKYBLUE (3375 -1025);
FORCEPROP 1 LAST MATERIAL X6S
J 0
(3375 -1075);
DISPLAY 0.617021 (3375 -1075);
PAINT SKYBLUE (3375 -1075);
FORCEPROP 1 LAST PACK_TYPE C0805
J 0
(3375 -1175);
DISPLAY 0.617021 (3375 -1175);
PAINT SKYBLUE (3375 -1175);
FORCEPROP 1 LAST VALUE 22UF
J 0
(3375 -925);
DISPLAY 0.617021 (3375 -925);
PAINT SKYBLUE (3375 -925);
FORCEPROP 1 LAST LOCATION PC1600
J 0
(3375 -875);
DISPLAY 0.574468 (3375 -875);
PAINT AQUA (3375 -875);
FORCEPROP 1 LASTPIN (3325 -875) $PN 1
J 0
(3335 -895);
DISPLAY 0.617021 (3335 -895);
PAINT MONO (3335 -895);
FORCEPROP 1 LASTPIN (3325 -1075) $PN 2
J 0
(3335 -1095);
DISPLAY 0.617021 (3335 -1095);
PAINT MONO (3335 -1095);
FORCEPROP 2 LAST CDS_LIB pure_quanta
J 0
(3325 -975);
DISPLAY INVISIBLE (3325 -975);
FORCEPROP 1 LAST PATH I136
J 0
(3375 -825);
DISPLAY 0.978723 (3375 -825);
PAINT WHITE (3375 -825);
DISPLAY INVISIBLE (3375 -825);
FORCEPROP 0 LAST $SEC 1
J 0
(3375 -825);
DISPLAY 0.680851 (3375 -825);
PAINT MONO (3375 -825);
DISPLAY INVISIBLE (3375 -825);
FORCEPROP 0 LAST CDS_SEC 1
J 0
(3375 -825);
DISPLAY 1.021277 (3375 -825);
DISPLAY INVISIBLE (3375 -825);
FORCEADD Q_CAP..1
(3725 -975);
FORCEPROP 1 LAST PART_NUMBER CH4104K1B00
J 0
(3775 -1125);
DISPLAY 0.617021 (3775 -1125);
PAINT BLUE (3775 -1125);
DISPLAY INVISIBLE (3775 -1125);
FORCEPROP 1 LAST TOLERANCE 10%
J 0
(3775 -1025);
DISPLAY 0.617021 (3775 -1025);
PAINT SKYBLUE (3775 -1025);
FORCEPROP 1 LAST PACK_TYPE 0402
J 0
(3775 -1175);
DISPLAY 0.617021 (3775 -1175);
PAINT SKYBLUE (3775 -1175);
FORCEPROP 1 LAST VALUE 0.1UF
J 0
(3775 -925);
DISPLAY 0.617021 (3775 -925);
PAINT SKYBLUE (3775 -925);
FORCEPROP 1 LAST MATERIAL X7R
J 0
(3775 -1075);
DISPLAY 0.617021 (3775 -1075);
PAINT SKYBLUE (3775 -1075);
FORCEPROP 1 LAST VOLTAGE 25V
J 0
(3775 -975);
DISPLAY 0.617021 (3775 -975);
PAINT SKYBLUE (3775 -975);
FORCEPROP 1 LAST LOCATION PC1869
J 0
(3775 -875);
DISPLAY 0.617021 (3775 -875);
PAINT AQUA (3775 -875);
FORCEPROP 1 LASTPIN (3725 -875) $PN 1
J 0
(3735 -895);
DISPLAY 0.617021 (3735 -895);
FORCEPROP 1 LASTPIN (3725 -1075) $PN 2
J 0
(3735 -1095);
DISPLAY 0.617021 (3735 -1095);
FORCEPROP 2 LAST CDS_LIB pure_quanta
J 0
(3725 -975);
PAINT MONO (3725 -975);
DISPLAY INVISIBLE (3725 -975);
FORCEPROP 1 LAST PATH I137
J 0
(3775 -825);
DISPLAY 0.978723 (3775 -825);
PAINT WHITE (3775 -825);
DISPLAY INVISIBLE (3775 -825);
FORCEPROP 2 LAST $SEC 1
J 0
(3775 -775);
DISPLAY 0.680851 (3775 -775);
PAINT MONO (3775 -775);
DISPLAY INVISIBLE (3775 -775);
FORCEPROP 2 LAST CDS_SEC 1
J 0
(3775 -775);
DISPLAY 1.021277 (3775 -775);
DISPLAY INVISIBLE (3775 -775);
FORCEADD UNIVERSAL_POWER..1
(4175 -450);
FORCEPROP 3 LASTPIN (4175 -500) SIG_NAME P3V3_AUX\g
J 0
(4185 -490);
DISPLAY 0.659574 (4185 -490);
PAINT MONO (4185 -490);
DISPLAY INVISIBLE (4185 -490);
FORCEPROP 1 LAST HDL_POWER P3V3_AUX
J 1
(4175 -400);
DISPLAY 0.617021 (4175 -400);
PAINT GREEN (4175 -400);
FORCEPROP 2 LAST CDS_LIB logical_power
J 0
(4175 -450);
PAINT MONO (4175 -450);
DISPLAY INVISIBLE (4175 -450);
FORCEPROP 1 LAST PATH I138
J 0
(4225 -425);
DISPLAY 0.872340 (4225 -425);
PAINT AQUA (4225 -425);
DISPLAY INVISIBLE (4225 -425);
FORCEADD Q_RES..2
(900 200);
FORCEPROP 1 LAST PART_NUMBER CS31002FB08
J 0
(940 25);
DISPLAY 0.617021 (940 25);
PAINT BLUE (940 25);
DISPLAY INVISIBLE (940 25);
FORCEPROP 1 LAST PACK_TYPE 0402LF
J 0
(940 75);
DISPLAY 0.617021 (940 75);
PAINT SKYBLUE (940 75);
FORCEPROP 1 LAST TOLERANCE 1%
J 0
(945 225);
DISPLAY 0.617021 (945 225);
PAINT SKYBLUE (945 225);
FORCEPROP 1 LAST VALUE 10K
J 0
(945 275);
DISPLAY 0.617021 (945 275);
PAINT SKYBLUE (945 275);
FORCEPROP 1 LAST WATTAGE 1/16W
J 0
(940 175);
DISPLAY 0.617021 (940 175);
PAINT SKYBLUE (940 175);
FORCEPROP 1 LAST MATERIAL CHIP
J 0
(940 125);
DISPLAY 0.617021 (940 125);
PAINT SKYBLUE (940 125);
FORCEPROP 1 LAST LOCATION PR73
J 0
(945 325);
DISPLAY 0.617021 (945 325);
PAINT AQUA (945 325);
FORCEPROP 1 LASTPIN (900 300) $PN 1
J 0
(905 262);
DISPLAY 0.617021 (905 262);
FORCEPROP 1 LASTPIN (900 100) $PN 2
J 0
(905 110);
DISPLAY 0.617021 (905 110);
FORCEPROP 2 LAST CDS_LIB pure_quanta
J 0
(900 200);
PAINT MONO (900 200);
DISPLAY INVISIBLE (900 200);
FORCEPROP 1 LAST PATH I139
J 0
(950 375);
DISPLAY 0.978723 (950 375);
PAINT WHITE (950 375);
DISPLAY INVISIBLE (950 375);
FORCEPROP 2 LAST $SEC 1
J 0
(950 425);
DISPLAY 0.680851 (950 425);
PAINT MONO (950 425);
DISPLAY INVISIBLE (950 425);
FORCEPROP 2 LAST CDS_SEC 1
J 0
(950 425);
DISPLAY 1.021277 (950 425);
DISPLAY INVISIBLE (950 425);
FORCEADD UNIVERSAL_POWER..1
(900 425);
FORCEPROP 3 LASTPIN (900 375) SIG_NAME P3V3_AUX\g
J 0
(910 385);
DISPLAY 0.659574 (910 385);
PAINT MONO (910 385);
DISPLAY INVISIBLE (910 385);
FORCEPROP 1 LAST HDL_POWER P3V3_AUX
J 1
(900 475);
DISPLAY 0.617021 (900 475);
PAINT GREEN (900 475);
FORCEPROP 2 LAST CDS_LIB logical_power
J 0
(900 425);
DISPLAY INVISIBLE (900 425);
FORCEPROP 1 LAST PATH I140
J 0
(950 450);
DISPLAY 0.872340 (950 450);
PAINT AQUA (950 450);
DISPLAY INVISIBLE (950 450);
FORCEADD Q_DIODE..1
(-3025 -775);
FORCEPROP 1 LAST PART_NUMBER BC000340033
J 0
(-3100 -645);
DISPLAY 0.723404 (-3100 -645);
PAINT GREEN (-3100 -645);
DISPLAY INVISIBLE (-3100 -645);
FORCEPROP 2 LAST PACK_TYPE SMLF
J 0
(-3100 -550);
DISPLAY 1.021277 (-3100 -550);
FORCEPROP 2 LAST VALUE SDMK0340L-7-F
J 0
(-3100 -500);
DISPLAY 1.021277 (-3100 -500);
FORCEPROP 1 LAST MATERIAL IC
J 0
(-3100 -700);
DISPLAY 0.723404 (-3100 -700);
PAINT GREEN (-3100 -700);
FORCEPROP 1 LAST $LOCATION D145
J 0
(-3100 -590);
DISPLAY 0.723404 (-3100 -590);
PAINT GREEN (-3100 -590);
FORCEPROP 0 LASTPIN (-3150 -775) $PN 1
J 2
(-3160 -765);
DISPLAY 0.680851 (-3160 -765);
PAINT MONO (-3160 -765);
FORCEPROP 0 LASTPIN (-2900 -775) $PN 2
J 0
(-2890 -765);
DISPLAY 0.680851 (-2890 -765);
PAINT MONO (-2890 -765);
FORCEPROP 2 LAST CDS_LIB pure_quanta
J 0
(-3025 -775);
DISPLAY INVISIBLE (-3025 -775);
FORCEPROP 1 LAST PIN_NAMES_ROTATE True
J 0
(-3100 -615);
DISPLAY 0.255319 (-3100 -615);
PAINT GREEN (-3100 -615);
DISPLAY INVISIBLE (-3100 -615);
FORCEPROP 1 LAST NEEDS_NO_SIZE TRUE
J 0
(-3025 -775);
DISPLAY 0.468085 (-3025 -775);
PAINT GREEN (-3025 -775);
DISPLAY INVISIBLE (-3025 -775);
FORCEPROP 1 LAST PATH I71
J 0
(-2925 -695);
DISPLAY 0.723404 (-2925 -695);
PAINT GREEN (-2925 -695);
DISPLAY INVISIBLE (-2925 -695);
FORCEPROP 0 LAST CDS_LOCATION D145
J 0
(-3100 -450);
DISPLAY 1.021277 (-3100 -450);
DISPLAY INVISIBLE (-3100 -450);
FORCEPROP 0 LAST $SEC 1
J 0
(-3100 -450);
DISPLAY 0.680851 (-3100 -450);
PAINT MONO (-3100 -450);
DISPLAY INVISIBLE (-3100 -450);
FORCEPROP 0 LAST CDS_SEC 1
J 0
(-3100 -450);
DISPLAY 1.021277 (-3100 -450);
DISPLAY INVISIBLE (-3100 -450);
FORCEADD Q_RES..2
(-3275 -1025);
FORCEPROP 1 LAST PART_NUMBER CS41002FB09
J 0
(-3235 -1150);
DISPLAY 0.638298 (-3235 -1150);
DISPLAY INVISIBLE (-3235 -1150);
FORCEPROP 1 LAST TOLERANCE 1%
J 0
(-3230 -1000);
DISPLAY 0.638298 (-3230 -1000);
FORCEPROP 1 LAST PACK_TYPE 0402LF
J 0
(-3235 -1200);
DISPLAY 0.638298 (-3235 -1200);
FORCEPROP 1 LAST MATERIAL CHIP
J 0
(-3235 -1100);
DISPLAY 0.638298 (-3235 -1100);
FORCEPROP 1 LAST WATTAGE 1/16W
J 0
(-3235 -1050);
DISPLAY 0.638298 (-3235 -1050);
FORCEPROP 1 LAST VALUE 100K
J 0
(-3230 -950);
DISPLAY 0.638298 (-3230 -950);
FORCEPROP 1 LAST LOCATION R1571
J 0
(-3230 -900);
DISPLAY 0.638298 (-3230 -900);
FORCEPROP 1 LASTPIN (-3275 -925) $PN 1
J 0
(-3270 -963);
DISPLAY 0.787234 (-3270 -963);
PAINT MONO (-3270 -963);
FORCEPROP 1 LASTPIN (-3275 -1125) $PN 2
J 0
(-3270 -1115);
DISPLAY 0.787234 (-3270 -1115);
PAINT MONO (-3270 -1115);
FORCEPROP 2 LAST CDS_LIB pure_quanta
J 0
(-3275 -1025);
DISPLAY INVISIBLE (-3275 -1025);
FORCEPROP 1 LAST PATH I72
J 0
(-3225 -850);
DISPLAY 0.978723 (-3225 -850);
PAINT WHITE (-3225 -850);
DISPLAY INVISIBLE (-3225 -850);
FORCEPROP 0 LAST $SEC 1
J 0
(-3225 -850);
DISPLAY 0.680851 (-3225 -850);
PAINT MONO (-3225 -850);
DISPLAY INVISIBLE (-3225 -850);
FORCEPROP 0 LAST CDS_SEC 1
J 0
(-3225 -850);
DISPLAY 1.021277 (-3225 -850);
DISPLAY INVISIBLE (-3225 -850);
FORCEADD Q_CAP..1
(-3225 -1600);
FORCEPROP 1 LAST PART_NUMBER CH4224K1B01
J 0
(-3175 -1750);
DISPLAY 0.617021 (-3175 -1750);
DISPLAY INVISIBLE (-3175 -1750);
FORCEPROP 1 LAST VOLTAGE 25V
J 0
(-3175 -1600);
DISPLAY 0.617021 (-3175 -1600);
FORCEPROP 1 LAST PACK_TYPE C0402
J 0
(-3175 -1800);
DISPLAY 0.617021 (-3175 -1800);
FORCEPROP 1 LAST VALUE 0.22UF
J 0
(-3175 -1550);
DISPLAY 0.617021 (-3175 -1550);
FORCEPROP 1 LAST MATERIAL X7R
J 0
(-3175 -1700);
DISPLAY 0.617021 (-3175 -1700);
FORCEPROP 1 LAST TOLERANCE 10%
J 0
(-3175 -1650);
DISPLAY 0.617021 (-3175 -1650);
FORCEPROP 1 LAST LOCATION C2541
J 0
(-3175 -1500);
DISPLAY 0.617021 (-3175 -1500);
FORCEPROP 1 LASTPIN (-3225 -1500) $PN 1
J 0
(-3215 -1520);
DISPLAY 0.787234 (-3215 -1520);
PAINT MONO (-3215 -1520);
FORCEPROP 1 LASTPIN (-3225 -1700) $PN 2
J 0
(-3215 -1720);
DISPLAY 0.787234 (-3215 -1720);
PAINT MONO (-3215 -1720);
FORCEPROP 2 LAST CDS_LIB pure_quanta
J 0
(-3225 -1600);
DISPLAY INVISIBLE (-3225 -1600);
FORCEPROP 1 LAST PATH I73
J 0
(-3175 -1450);
DISPLAY 0.978723 (-3175 -1450);
PAINT WHITE (-3175 -1450);
DISPLAY INVISIBLE (-3175 -1450);
FORCEPROP 0 LAST $SEC 1
J 0
(-3175 -1450);
DISPLAY 0.680851 (-3175 -1450);
PAINT MONO (-3175 -1450);
DISPLAY INVISIBLE (-3175 -1450);
FORCEPROP 0 LAST CDS_SEC 1
J 0
(-3175 -1450);
DISPLAY 1.021277 (-3175 -1450);
DISPLAY INVISIBLE (-3175 -1450);
FORCEADD GND..1
(-3225 -1900);
FORCEPROP 3 LASTPIN (-3225 -1850) SIG_NAME GND\g
J 0
(-3215 -1840);
DISPLAY 0.659574 (-3215 -1840);
PAINT MONO (-3215 -1840);
DISPLAY INVISIBLE (-3215 -1840);
FORCEPROP 1 LAST SIZE 1B
J 0
(-3150 -1950);
DISPLAY 0.872340 (-3150 -1950);
PAINT AQUA (-3150 -1950);
DISPLAY INVISIBLE (-3150 -1950);
FORCEPROP 2 LAST CDS_LIB logical_power
J 0
(-3225 -1900);
DISPLAY INVISIBLE (-3225 -1900);
FORCEPROP 1 LAST HDL_POWER GND
J 0
(-3225 -1750);
DISPLAY 0.872340 (-3225 -1750);
PAINT GREEN (-3225 -1750);
DISPLAY INVISIBLE (-3225 -1750);
FORCEPROP 1 LAST PATH I74
J 0
(-3150 -1900);
DISPLAY 0.872340 (-3150 -1900);
PAINT AQUA (-3150 -1900);
DISPLAY INVISIBLE (-3150 -1900);
FORCEADD GND..1
(-3825 -1825);
FORCEPROP 3 LASTPIN (-3825 -1775) SIG_NAME GND\g
J 0
(-3815 -1765);
DISPLAY 0.659574 (-3815 -1765);
PAINT MONO (-3815 -1765);
DISPLAY INVISIBLE (-3815 -1765);
FORCEPROP 1 LAST PATH I75
J 0
(-3750 -1825);
DISPLAY 0.872340 (-3750 -1825);
PAINT AQUA (-3750 -1825);
DISPLAY INVISIBLE (-3750 -1825);
FORCEPROP 1 LAST HDL_POWER GND
J 0
(-3825 -1675);
DISPLAY 0.872340 (-3825 -1675);
PAINT GREEN (-3825 -1675);
DISPLAY INVISIBLE (-3825 -1675);
FORCEPROP 1 LAST SIZE 1B
J 0
(-3750 -1875);
DISPLAY 0.872340 (-3750 -1875);
PAINT AQUA (-3750 -1875);
DISPLAY INVISIBLE (-3750 -1875);
FORCEPROP 2 LAST CDS_LIB logical_power
J 0
(-3825 -1825);
DISPLAY INVISIBLE (-3825 -1825);
FORCEADD Q_RES..2
(-3825 -1525);
FORCEPROP 1 LAST PART_NUMBER CS38662FB05
J 0
(-3785 -1650);
DISPLAY 0.787234 (-3785 -1650);
DISPLAY INVISIBLE (-3785 -1650);
FORCEPROP 1 LAST PACK_TYPE 0402LF
J 0
(-3785 -1700);
DISPLAY 0.787234 (-3785 -1700);
FORCEPROP 1 LAST MATERIAL EMPTY
J 0
(-3785 -1600);
DISPLAY 0.787234 (-3785 -1600);
PAINT RED (-3785 -1600);
FORCEPROP 1 LAST WATTAGE 1/16W
J 0
(-3785 -1550);
DISPLAY 0.787234 (-3785 -1550);
FORCEPROP 1 LAST VALUE 86.6K
J 0
(-3780 -1450);
DISPLAY 0.787234 (-3780 -1450);
FORCEPROP 1 LAST TOLERANCE 1%
J 0
(-3780 -1500);
DISPLAY 0.787234 (-3780 -1500);
FORCEPROP 1 LAST $LOCATION R3118
J 0
(-3780 -1400);
DISPLAY 0.787234 (-3780 -1400);
FORCEPROP 1 LASTPIN (-3825 -1425) $PN 1
J 0
(-3820 -1463);
DISPLAY 0.787234 (-3820 -1463);
PAINT MONO (-3820 -1463);
FORCEPROP 1 LASTPIN (-3825 -1625) $PN 2
J 0
(-3820 -1615);
DISPLAY 0.787234 (-3820 -1615);
PAINT MONO (-3820 -1615);
FORCEPROP 1 LAST PATH I76
J 0
(-3775 -1350);
DISPLAY 0.978723 (-3775 -1350);
PAINT WHITE (-3775 -1350);
DISPLAY INVISIBLE (-3775 -1350);
FORCEPROP 2 LAST CDS_LIB pure_quanta
J 0
(-3825 -1525);
DISPLAY INVISIBLE (-3825 -1525);
FORCEPROP 0 LAST CDS_LOCATION R3118
J 0
(-3775 -1350);
DISPLAY 1.021277 (-3775 -1350);
DISPLAY INVISIBLE (-3775 -1350);
FORCEPROP 0 LAST $SEC 1
J 0
(-3775 -1350);
DISPLAY 0.680851 (-3775 -1350);
PAINT MONO (-3775 -1350);
DISPLAY INVISIBLE (-3775 -1350);
FORCEPROP 0 LAST CDS_SEC 1
J 0
(-3775 -1350);
DISPLAY 1.021277 (-3775 -1350);
DISPLAY INVISIBLE (-3775 -1350);
FORCEADD GND..1
(-4050 -150);
FORCEPROP 3 LASTPIN (-4050 -100) SIG_NAME GND\g
J 0
(-4040 -90);
DISPLAY 0.659574 (-4040 -90);
PAINT MONO (-4040 -90);
DISPLAY INVISIBLE (-4040 -90);
FORCEPROP 1 LAST HDL_POWER GND
J 0
(-4050 0);
DISPLAY 0.872340 (-4050 0);
PAINT GREEN (-4050 0);
DISPLAY INVISIBLE (-4050 0);
FORCEPROP 2 LAST CDS_LIB logical_power
J 0
(-4050 -150);
DISPLAY INVISIBLE (-4050 -150);
FORCEPROP 1 LAST SIZE 1B
J 0
(-3975 -200);
DISPLAY 0.872340 (-3975 -200);
PAINT AQUA (-3975 -200);
DISPLAY INVISIBLE (-3975 -200);
FORCEPROP 1 LAST PATH I77
J 0
(-3975 -150);
DISPLAY 0.872340 (-3975 -150);
PAINT AQUA (-3975 -150);
DISPLAY INVISIBLE (-3975 -150);
FORCEADD Q_RES..2
(-3825 -950);
FORCEPROP 1 LAST PART_NUMBER CS45102JB03
J 0
(-3785 -1075);
DISPLAY 0.787234 (-3785 -1075);
DISPLAY INVISIBLE (-3785 -1075);
FORCEPROP 1 LAST WATTAGE 1/16W
J 0
(-3785 -975);
DISPLAY 0.787234 (-3785 -975);
FORCEPROP 1 LAST MATERIAL EMPTY
J 0
(-3785 -1025);
DISPLAY 0.787234 (-3785 -1025);
PAINT RED (-3785 -1025);
FORCEPROP 1 LAST TOLERANCE 5%
J 0
(-3780 -925);
DISPLAY 0.787234 (-3780 -925);
FORCEPROP 1 LAST VALUE 510K
J 0
(-3780 -875);
DISPLAY 0.787234 (-3780 -875);
FORCEPROP 1 LAST PACK_TYPE 0402LF
J 0
(-3785 -1125);
DISPLAY 0.787234 (-3785 -1125);
FORCEPROP 1 LAST $LOCATION R3117
J 0
(-3780 -825);
DISPLAY 0.787234 (-3780 -825);
FORCEPROP 1 LASTPIN (-3825 -850) $PN 1
J 0
(-3820 -888);
DISPLAY 0.787234 (-3820 -888);
PAINT MONO (-3820 -888);
FORCEPROP 1 LASTPIN (-3825 -1050) $PN 2
J 0
(-3820 -1040);
DISPLAY 0.787234 (-3820 -1040);
PAINT MONO (-3820 -1040);
FORCEPROP 1 LAST PATH I78
J 0
(-3775 -775);
DISPLAY 0.978723 (-3775 -775);
PAINT WHITE (-3775 -775);
DISPLAY INVISIBLE (-3775 -775);
FORCEPROP 2 LAST CDS_LIB pure_quanta
J 0
(-3825 -950);
DISPLAY INVISIBLE (-3825 -950);
FORCEPROP 0 LAST CDS_LOCATION R3117
J 0
(-3775 -775);
DISPLAY 1.021277 (-3775 -775);
DISPLAY INVISIBLE (-3775 -775);
FORCEPROP 0 LAST $SEC 1
J 0
(-3775 -775);
DISPLAY 0.680851 (-3775 -775);
PAINT MONO (-3775 -775);
DISPLAY INVISIBLE (-3775 -775);
FORCEPROP 0 LAST CDS_SEC 1
J 0
(-3775 -775);
DISPLAY 1.021277 (-3775 -775);
DISPLAY INVISIBLE (-3775 -775);
FORCEADD OFFPAGE..1
(-3850 -375);
FORCEPROP 2 LAST $XR3 247 
J 0
(-4462 -375);
DISPLAY 0.638298 (-4462 -375);
PAINT MONO (-4462 -375);
FORCEPROP 2 LAST $XR2 214 
J 0
(-4342 -375);
DISPLAY 0.638298 (-4342 -375);
PAINT MONO (-4342 -375);
FORCEPROP 2 LAST $XR1 305 
J 0
(-4222 -375);
DISPLAY 0.638298 (-4222 -375);
PAINT MONO (-4222 -375);
FORCEPROP 2 LAST $XR0 301 
J 0
(-4102 -375);
DISPLAY 0.638298 (-4102 -375);
PAINT MONO (-4102 -375);
FORCEPROP 2 LAST PATH I79
J 0
(-4100 -325);
DISPLAY 1.021277 (-4100 -325);
DISPLAY INVISIBLE (-4100 -325);
FORCEPROP 1 LAST COMMENT_BODY TRUE
J 0
(-3725 -475);
DISPLAY 0.872340 (-3725 -475);
PAINT GREEN (-3725 -475);
DISPLAY INVISIBLE (-3725 -475);
FORCEPROP 1 LAST OFFPAGE TRUE
J 0
(-3525 -500);
DISPLAY 0.872340 (-3525 -500);
PAINT GREEN (-3525 -500);
DISPLAY INVISIBLE (-3525 -500);
FORCEPROP 2 LAST CDS_LIB standard
J 0
(-3850 -375);
DISPLAY INVISIBLE (-3850 -375);
FORCEADD P1V0_AUX..1
(-3825 -625);
FORCEPROP 3 LASTPIN (-3825 -675) SIG_NAME P12V_AUX\g
J 0
(-3815 -665);
DISPLAY 0.659574 (-3815 -665);
PAINT MONO (-3815 -665);
DISPLAY INVISIBLE (-3815 -665);
FORCEPROP 1 LAST HDL_POWER P12V_AUX
J 1
(-3814 -578);
DISPLAY 0.617021 (-3814 -578);
PAINT GREEN (-3814 -578);
FORCEPROP 1 LAST PATH I80
J 0
(-3775 -600);
DISPLAY 0.872340 (-3775 -600);
PAINT AQUA (-3775 -600);
DISPLAY INVISIBLE (-3775 -600);
FORCEPROP 2 LAST ROOM VR_DDR1_POWER_STAGE
J 0
(-3825 -525);
DISPLAY 0.978723 (-3825 -525);
DISPLAY INVISIBLE (-3825 -525);
FORCEPROP 2 LAST CDS_LIB logical_power
J 0
(-3825 -625);
DISPLAY INVISIBLE (-3825 -625);
FORCEADD GND..1
(-2150 -1400);
FORCEPROP 3 LASTPIN (-2150 -1350) SIG_NAME GND\g
J 0
(-2140 -1340);
DISPLAY 0.659574 (-2140 -1340);
PAINT MONO (-2140 -1340);
DISPLAY INVISIBLE (-2140 -1340);
FORCEPROP 1 LAST HDL_POWER GND
J 0
(-2150 -1250);
DISPLAY 0.872340 (-2150 -1250);
PAINT GREEN (-2150 -1250);
DISPLAY INVISIBLE (-2150 -1250);
FORCEPROP 2 LAST CDS_LIB logical_power
J 0
(-2150 -1400);
DISPLAY INVISIBLE (-2150 -1400);
FORCEPROP 1 LAST SIZE 1B
J 0
(-2075 -1450);
DISPLAY 0.872340 (-2075 -1450);
PAINT AQUA (-2075 -1450);
DISPLAY INVISIBLE (-2075 -1450);
FORCEPROP 1 LAST PATH I83
J 0
(-2075 -1400);
DISPLAY 0.872340 (-2075 -1400);
PAINT AQUA (-2075 -1400);
DISPLAY INVISIBLE (-2075 -1400);
FORCEADD Q_RES..2
(-2150 -1225);
FORCEPROP 1 LAST PART_NUMBER CS00002JB13
J 0
(-2110 -1350);
DISPLAY 0.617021 (-2110 -1350);
PAINT BLUE (-2110 -1350);
DISPLAY INVISIBLE (-2110 -1350);
FORCEPROP 1 LAST MATERIAL CHIP
J 0
(-2110 -1300);
DISPLAY 0.617021 (-2110 -1300);
PAINT SKYBLUE (-2110 -1300);
FORCEPROP 1 LAST TOLERANCE 5%
J 0
(-2105 -1200);
DISPLAY 0.617021 (-2105 -1200);
PAINT SKYBLUE (-2105 -1200);
FORCEPROP 1 LAST WATTAGE 1/16W
J 0
(-2110 -1250);
DISPLAY 0.617021 (-2110 -1250);
PAINT SKYBLUE (-2110 -1250);
FORCEPROP 1 LAST VALUE 0
J 0
(-2105 -1150);
DISPLAY 0.617021 (-2105 -1150);
PAINT SKYBLUE (-2105 -1150);
FORCEPROP 1 LAST PACK_TYPE 0402LF
J 0
(-2110 -1400);
DISPLAY 0.617021 (-2110 -1400);
PAINT SKYBLUE (-2110 -1400);
FORCEPROP 1 LAST LOCATION PR832
J 0
(-2105 -1100);
DISPLAY 0.617021 (-2105 -1100);
PAINT AQUA (-2105 -1100);
FORCEPROP 1 LASTPIN (-2150 -1125) $PN 1
J 0
(-2145 -1163);
DISPLAY 0.617021 (-2145 -1163);
PAINT MONO (-2145 -1163);
FORCEPROP 1 LASTPIN (-2150 -1325) $PN 2
J 0
(-2145 -1315);
DISPLAY 0.617021 (-2145 -1315);
PAINT MONO (-2145 -1315);
FORCEPROP 2 LAST CDS_LIB pure_quanta
J 0
(-2150 -1225);
DISPLAY INVISIBLE (-2150 -1225);
FORCEPROP 1 LAST PATH I84
J 0
(-2100 -1050);
DISPLAY 0.978723 (-2100 -1050);
PAINT WHITE (-2100 -1050);
DISPLAY INVISIBLE (-2100 -1050);
FORCEPROP 0 LAST $SEC 1
J 0
(-2100 -1050);
DISPLAY 0.680851 (-2100 -1050);
PAINT MONO (-2100 -1050);
DISPLAY INVISIBLE (-2100 -1050);
FORCEPROP 0 LAST CDS_SEC 1
J 0
(-2100 -1050);
DISPLAY 1.021277 (-2100 -1050);
DISPLAY INVISIBLE (-2100 -1050);
FORCEADD Q_CAP..1
(-2050 -625);
FORCEPROP 1 LAST PART_NUMBER CH5473KE902
J 0
(-2000 -775);
DISPLAY 0.617021 (-2000 -775);
PAINT BLUE (-2000 -775);
DISPLAY INVISIBLE (-2000 -775);
FORCEPROP 1 LAST PACK_TYPE C0603
J 0
(-2000 -825);
DISPLAY 0.617021 (-2000 -825);
PAINT SKYBLUE (-2000 -825);
FORCEPROP 1 LAST VALUE 4.7UF
J 0
(-2000 -575);
DISPLAY 0.617021 (-2000 -575);
PAINT SKYBLUE (-2000 -575);
FORCEPROP 1 LAST VOLTAGE 16V
J 0
(-2000 -625);
DISPLAY 0.617021 (-2000 -625);
PAINT SKYBLUE (-2000 -625);
FORCEPROP 1 LAST TOLERANCE 10%
J 0
(-2000 -675);
DISPLAY 0.617021 (-2000 -675);
PAINT SKYBLUE (-2000 -675);
FORCEPROP 1 LAST MATERIAL X6S
J 0
(-2000 -725);
DISPLAY 0.617021 (-2000 -725);
PAINT SKYBLUE (-2000 -725);
FORCEPROP 1 LAST LOCATION PC581
J 0
(-2000 -525);
DISPLAY 0.617021 (-2000 -525);
PAINT AQUA (-2000 -525);
FORCEPROP 1 LASTPIN (-2050 -525) $PN 1
J 0
(-2040 -545);
DISPLAY 0.617021 (-2040 -545);
PAINT MONO (-2040 -545);
FORCEPROP 1 LASTPIN (-2050 -725) $PN 2
J 0
(-2040 -745);
DISPLAY 0.617021 (-2040 -745);
PAINT MONO (-2040 -745);
FORCEPROP 2 LAST CDS_LIB pure_quanta
J 0
(-2050 -625);
DISPLAY INVISIBLE (-2050 -625);
FORCEPROP 1 LAST PATH I86
J 0
(-2000 -475);
DISPLAY 0.978723 (-2000 -475);
PAINT WHITE (-2000 -475);
DISPLAY INVISIBLE (-2000 -475);
FORCEPROP 0 LAST $SEC 1
J 0
(-2000 -475);
DISPLAY 0.680851 (-2000 -475);
PAINT MONO (-2000 -475);
DISPLAY INVISIBLE (-2000 -475);
FORCEPROP 0 LAST CDS_SEC 1
J 0
(-2000 -475);
DISPLAY 1.021277 (-2000 -475);
DISPLAY INVISIBLE (-2000 -475);
FORCEADD GND..1
(-2050 -850);
FORCEPROP 3 LASTPIN (-2050 -800) SIG_NAME GND\g
J 0
(-2040 -790);
DISPLAY 0.659574 (-2040 -790);
PAINT MONO (-2040 -790);
DISPLAY INVISIBLE (-2040 -790);
FORCEPROP 1 LAST HDL_POWER GND
J 0
(-2050 -700);
DISPLAY 0.872340 (-2050 -700);
PAINT GREEN (-2050 -700);
DISPLAY INVISIBLE (-2050 -700);
FORCEPROP 2 LAST CDS_LIB logical_power
J 0
(-2050 -850);
DISPLAY INVISIBLE (-2050 -850);
FORCEPROP 1 LAST SIZE 1B
J 0
(-1975 -900);
DISPLAY 0.872340 (-1975 -900);
PAINT AQUA (-1975 -900);
DISPLAY INVISIBLE (-1975 -900);
FORCEPROP 1 LAST PATH I87
J 0
(-1975 -850);
DISPLAY 0.872340 (-1975 -850);
PAINT AQUA (-1975 -850);
DISPLAY INVISIBLE (-1975 -850);
FORCEADD GND..1
(-1750 -1525);
FORCEPROP 3 LASTPIN (-1750 -1475) SIG_NAME GND\g
J 0
(-1740 -1465);
DISPLAY 0.659574 (-1740 -1465);
PAINT MONO (-1740 -1465);
DISPLAY INVISIBLE (-1740 -1465);
FORCEPROP 1 LAST HDL_POWER GND
J 0
(-1750 -1375);
DISPLAY 0.872340 (-1750 -1375);
PAINT GREEN (-1750 -1375);
DISPLAY INVISIBLE (-1750 -1375);
FORCEPROP 1 LAST SIZE 1B
J 0
(-1675 -1575);
DISPLAY 0.872340 (-1675 -1575);
PAINT AQUA (-1675 -1575);
DISPLAY INVISIBLE (-1675 -1575);
FORCEPROP 2 LAST CDS_LIB logical_power
J 0
(-1750 -1525);
DISPLAY INVISIBLE (-1750 -1525);
FORCEPROP 1 LAST PATH I88
J 0
(-1675 -1525);
DISPLAY 0.872340 (-1675 -1525);
PAINT AQUA (-1675 -1525);
DISPLAY INVISIBLE (-1675 -1525);
FORCEADD Q_RES..2
(-1750 -1325);
FORCEPROP 1 LAST PART_NUMBER CS21502FB07
J 0
(-1725 -1450);
DISPLAY 0.617021 (-1725 -1450);
PAINT BLUE (-1725 -1450);
DISPLAY INVISIBLE (-1725 -1450);
FORCEPROP 1 LAST TOLERANCE 1%
J 0
(-1705 -1300);
DISPLAY 0.617021 (-1705 -1300);
PAINT SKYBLUE (-1705 -1300);
FORCEPROP 1 LAST VALUE 1.5K
J 0
(-1705 -1250);
DISPLAY 0.617021 (-1705 -1250);
PAINT SKYBLUE (-1705 -1250);
FORCEPROP 1 LAST PACK_TYPE 0402LF
J 0
(-1710 -1500);
DISPLAY 0.617021 (-1710 -1500);
PAINT SKYBLUE (-1710 -1500);
FORCEPROP 1 LAST MATERIAL EMPTY
J 0
(-1710 -1400);
DISPLAY 0.617021 (-1710 -1400);
PAINT RED (-1710 -1400);
FORCEPROP 1 LAST WATTAGE 1/16W
J 0
(-1710 -1350);
DISPLAY 0.617021 (-1710 -1350);
PAINT SKYBLUE (-1710 -1350);
FORCEPROP 1 LAST LOCATION PR833
J 0
(-1705 -1200);
DISPLAY 0.617021 (-1705 -1200);
PAINT AQUA (-1705 -1200);
FORCEPROP 1 LASTPIN (-1750 -1225) $PN 1
J 0
(-1745 -1263);
DISPLAY 0.617021 (-1745 -1263);
PAINT MONO (-1745 -1263);
FORCEPROP 1 LASTPIN (-1750 -1425) $PN 2
J 0
(-1745 -1415);
DISPLAY 0.617021 (-1745 -1415);
PAINT MONO (-1745 -1415);
FORCEPROP 2 LAST CDS_LIB pure_quanta
J 0
(-1750 -1325);
DISPLAY INVISIBLE (-1750 -1325);
FORCEPROP 1 LAST PATH I89
J 0
(-1700 -1150);
DISPLAY 0.978723 (-1700 -1150);
PAINT WHITE (-1700 -1150);
DISPLAY INVISIBLE (-1700 -1150);
FORCEPROP 0 LAST $SEC 1
J 0
(-1700 -1150);
DISPLAY 0.680851 (-1700 -1150);
PAINT MONO (-1700 -1150);
DISPLAY INVISIBLE (-1700 -1150);
FORCEPROP 0 LAST CDS_SEC 1
J 0
(-1700 -1150);
DISPLAY 1.021277 (-1700 -1150);
DISPLAY INVISIBLE (-1700 -1150);
FORCEADD GND..1
(-1350 -1625);
FORCEPROP 3 LASTPIN (-1350 -1575) SIG_NAME GND\g
J 0
(-1340 -1565);
DISPLAY 0.659574 (-1340 -1565);
PAINT MONO (-1340 -1565);
DISPLAY INVISIBLE (-1340 -1565);
FORCEPROP 1 LAST HDL_POWER GND
J 0
(-1350 -1475);
DISPLAY 0.872340 (-1350 -1475);
PAINT GREEN (-1350 -1475);
DISPLAY INVISIBLE (-1350 -1475);
FORCEPROP 2 LAST CDS_LIB logical_power
J 0
(-1350 -1625);
DISPLAY INVISIBLE (-1350 -1625);
FORCEPROP 1 LAST SIZE 1B
J 0
(-1275 -1675);
DISPLAY 0.872340 (-1275 -1675);
PAINT AQUA (-1275 -1675);
DISPLAY INVISIBLE (-1275 -1675);
FORCEPROP 1 LAST PATH I90
J 0
(-1275 -1625);
DISPLAY 0.872340 (-1275 -1625);
PAINT AQUA (-1275 -1625);
DISPLAY INVISIBLE (-1275 -1625);
FORCEADD Q_RES..2
(-1350 -1425);
FORCEPROP 1 LAST PART_NUMBER CS32152FB04
J 0
(-1305 -1550);
DISPLAY 0.617021 (-1305 -1550);
PAINT BLUE (-1305 -1550);
DISPLAY INVISIBLE (-1305 -1550);
FORCEPROP 1 LAST PACK_TYPE 0402LF
J 0
(-1300 -1600);
DISPLAY 0.617021 (-1300 -1600);
PAINT SKYBLUE (-1300 -1600);
FORCEPROP 1 LAST MATERIAL CHIP
J 0
(-1305 -1500);
DISPLAY 0.617021 (-1305 -1500);
PAINT SKYBLUE (-1305 -1500);
FORCEPROP 1 LAST TOLERANCE 1%
J 0
(-1300 -1400);
DISPLAY 0.617021 (-1300 -1400);
PAINT SKYBLUE (-1300 -1400);
FORCEPROP 1 LAST WATTAGE 1/16W
J 0
(-1305 -1450);
DISPLAY 0.617021 (-1305 -1450);
PAINT SKYBLUE (-1305 -1450);
FORCEPROP 1 LAST VALUE 21.5K
J 0
(-1300 -1350);
DISPLAY 0.617021 (-1300 -1350);
PAINT SKYBLUE (-1300 -1350);
FORCEPROP 1 LAST LOCATION PR834
J 0
(-1300 -1300);
DISPLAY 0.617021 (-1300 -1300);
PAINT AQUA (-1300 -1300);
FORCEPROP 1 LASTPIN (-1350 -1325) $PN 1
J 0
(-1345 -1363);
DISPLAY 0.617021 (-1345 -1363);
PAINT MONO (-1345 -1363);
FORCEPROP 1 LASTPIN (-1350 -1525) $PN 2
J 0
(-1345 -1515);
DISPLAY 0.617021 (-1345 -1515);
PAINT MONO (-1345 -1515);
FORCEPROP 2 LAST CDS_LIB pure_quanta
J 0
(-1350 -1425);
DISPLAY INVISIBLE (-1350 -1425);
FORCEPROP 1 LAST PATH I91
J 0
(-1300 -1250);
DISPLAY 0.978723 (-1300 -1250);
PAINT WHITE (-1300 -1250);
DISPLAY INVISIBLE (-1300 -1250);
FORCEPROP 0 LAST $SEC 1
J 0
(-1300 -1250);
DISPLAY 0.680851 (-1300 -1250);
PAINT MONO (-1300 -1250);
DISPLAY INVISIBLE (-1300 -1250);
FORCEPROP 0 LAST CDS_SEC 1
J 0
(-1300 -1250);
DISPLAY 1.021277 (-1300 -1250);
DISPLAY INVISIBLE (-1300 -1250);
FORCEADD GND..1
(-1625 -850);
FORCEPROP 3 LASTPIN (-1625 -800) SIG_NAME GND\g
J 0
(-1615 -790);
DISPLAY 0.659574 (-1615 -790);
PAINT MONO (-1615 -790);
DISPLAY INVISIBLE (-1615 -790);
FORCEPROP 1 LAST HDL_POWER GND
J 0
(-1625 -700);
DISPLAY 0.872340 (-1625 -700);
PAINT GREEN (-1625 -700);
DISPLAY INVISIBLE (-1625 -700);
FORCEPROP 1 LAST SIZE 1B
J 0
(-1550 -900);
DISPLAY 0.872340 (-1550 -900);
PAINT AQUA (-1550 -900);
DISPLAY INVISIBLE (-1550 -900);
FORCEPROP 2 LAST CDS_LIB logical_power
J 0
(-1625 -850);
DISPLAY INVISIBLE (-1625 -850);
FORCEPROP 1 LAST PATH I92
J 0
(-1550 -850);
DISPLAY 0.872340 (-1550 -850);
PAINT AQUA (-1550 -850);
DISPLAY INVISIBLE (-1550 -850);
FORCEADD Q_CAP..1
(-1625 -625);
FORCEPROP 1 LAST PART_NUMBER CH5223KE901
J 0
(-1575 -775);
DISPLAY 0.617021 (-1575 -775);
PAINT BLUE (-1575 -775);
DISPLAY INVISIBLE (-1575 -775);
FORCEPROP 1 LAST PACK_TYPE C0603
J 0
(-1575 -825);
DISPLAY 0.617021 (-1575 -825);
PAINT SKYBLUE (-1575 -825);
FORCEPROP 1 LAST MATERIAL X6S
J 0
(-1575 -725);
DISPLAY 0.617021 (-1575 -725);
PAINT SKYBLUE (-1575 -725);
FORCEPROP 1 LAST VOLTAGE 16V
J 0
(-1575 -625);
DISPLAY 0.617021 (-1575 -625);
PAINT SKYBLUE (-1575 -625);
FORCEPROP 1 LAST VALUE 2.2UF
J 0
(-1575 -575);
DISPLAY 0.617021 (-1575 -575);
PAINT SKYBLUE (-1575 -575);
FORCEPROP 1 LAST TOLERANCE 10%
J 0
(-1575 -675);
DISPLAY 0.617021 (-1575 -675);
PAINT SKYBLUE (-1575 -675);
FORCEPROP 1 LAST LOCATION PC591
J 0
(-1575 -525);
DISPLAY 0.617021 (-1575 -525);
PAINT AQUA (-1575 -525);
FORCEPROP 1 LASTPIN (-1625 -525) $PN 1
J 0
(-1615 -545);
DISPLAY 0.617021 (-1615 -545);
PAINT MONO (-1615 -545);
FORCEPROP 1 LASTPIN (-1625 -725) $PN 2
J 0
(-1615 -745);
DISPLAY 0.617021 (-1615 -745);
PAINT MONO (-1615 -745);
FORCEPROP 2 LAST CDS_LIB pure_quanta
J 0
(-1625 -625);
DISPLAY INVISIBLE (-1625 -625);
FORCEPROP 1 LAST PATH I93
J 0
(-1575 -475);
DISPLAY 0.978723 (-1575 -475);
PAINT WHITE (-1575 -475);
DISPLAY INVISIBLE (-1575 -475);
FORCEPROP 0 LAST $SEC 1
J 0
(-1575 -475);
DISPLAY 0.680851 (-1575 -475);
PAINT MONO (-1575 -475);
DISPLAY INVISIBLE (-1575 -475);
FORCEPROP 0 LAST CDS_SEC 1
J 0
(-1575 -475);
DISPLAY 1.021277 (-1575 -475);
DISPLAY INVISIBLE (-1575 -475);
FORCEADD Q_RES..1
(-1800 -400);
FORCEPROP 1 LAST PART_NUMBER CS-1002FB04
J 0
(-1850 -300);
DISPLAY 0.617021 (-1850 -300);
PAINT BLUE (-1850 -300);
DISPLAY INVISIBLE (-1850 -300);
FORCEPROP 1 LAST TOLERANCE 1%
J 0
(-1675 -350);
DISPLAY 0.617021 (-1675 -350);
PAINT SKYBLUE (-1675 -350);
FORCEPROP 1 LAST VALUE 1
J 2
(-1650 -400);
DISPLAY 0.617021 (-1650 -400);
PAINT SKYBLUE (-1650 -400);
FORCEPROP 1 LAST MATERIAL CHIP
J 0
(-1575 -400);
DISPLAY 0.617021 (-1575 -400);
PAINT SKYBLUE (-1575 -400);
FORCEPROP 1 LAST PACK_TYPE 0402LF
J 0
(-1425 -400);
DISPLAY 0.617021 (-1425 -400);
PAINT SKYBLUE (-1425 -400);
FORCEPROP 1 LAST WATTAGE 1/16W
J 2
(-1450 -350);
DISPLAY 0.617021 (-1450 -350);
PAINT SKYBLUE (-1450 -350);
FORCEPROP 1 LAST LOCATION PR389
J 0
(-1850 -350);
DISPLAY 0.617021 (-1850 -350);
PAINT AQUA (-1850 -350);
FORCEPROP 1 LASTPIN (-1900 -400) $PN 1
J 0
(-1888 -388);
DISPLAY 0.617021 (-1888 -388);
PAINT MONO (-1888 -388);
FORCEPROP 1 LASTPIN (-1700 -400) $PN 2
J 0
(-1738 -388);
DISPLAY 0.617021 (-1738 -388);
PAINT MONO (-1738 -388);
FORCEPROP 2 LAST CDS_LIB pure_quanta
J 0
(-1800 -400);
DISPLAY INVISIBLE (-1800 -400);
FORCEPROP 1 LAST PATH I94
J 0
(-1850 -250);
DISPLAY 0.978723 (-1850 -250);
PAINT WHITE (-1850 -250);
DISPLAY INVISIBLE (-1850 -250);
FORCEPROP 0 LAST $SEC 1
J 0
(-1850 -300);
DISPLAY 0.680851 (-1850 -300);
PAINT MONO (-1850 -300);
DISPLAY INVISIBLE (-1850 -300);
FORCEPROP 0 LAST CDS_SEC 1
J 0
(-1850 -300);
DISPLAY 1.021277 (-1850 -300);
DISPLAY INVISIBLE (-1850 -300);
FORCEADD IR3889MTRPBF..1
(-100 -750);
FORCEPROP 1 LAST PART_NUMBER AL003889000
J 0
(-400 50);
DISPLAY 0.723404 (-400 50);
PAINT GREEN (-400 50);
DISPLAY INVISIBLE (-400 50);
FORCEPROP 1 LAST MATERIAL IC
J 0
(-400 -25);
DISPLAY 0.723404 (-400 -25);
PAINT GREEN (-400 -25);
FORCEPROP 2 LAST VALUE IR3889MTRPBF
J 0
(-400 175);
DISPLAY 0.617021 (-400 175);
PAINT SKYBLUE (-400 175);
FORCEPROP 2 LAST PART_TYPE SMLF
J 0
(-400 225);
DISPLAY 1.021277 (-400 225);
FORCEPROP 1 LAST LOCATION PU9
J 0
(-400 125);
DISPLAY 0.723404 (-400 125);
PAINT GREEN (-400 125);
FORCEPROP 2 LASTPIN (300 -1350) $PN 32
J 0
(310 -1340);
DISPLAY 0.680851 (310 -1340);
PAINT MONO (310 -1340);
FORCEPROP 2 LASTPIN (300 -350) $PN 26
J 0
(310 -340);
DISPLAY 0.680851 (310 -340);
PAINT MONO (310 -340);
FORCEPROP 2 LASTPIN (-550 -550) $PN 27
J 2
(-560 -540);
DISPLAY 0.680851 (-560 -540);
PAINT MONO (-560 -540);
FORCEPROP 2 LASTPIN (300 -950) $PN 30
J 0
(310 -940);
DISPLAY 0.680851 (310 -940);
PAINT MONO (310 -940);
FORCEPROP 2 LASTPIN (-550 -700) $PN 6
J 2
(-560 -690);
DISPLAY 0.680851 (-560 -690);
PAINT MONO (-560 -690);
FORCEPROP 2 LASTPIN (-550 -750) $PN 37
J 2
(-560 -740);
DISPLAY 0.680851 (-560 -740);
PAINT MONO (-560 -740);
FORCEPROP 2 LASTPIN (-550 -1200) $PN 1
J 2
(-560 -1190);
DISPLAY 0.680851 (-560 -1190);
PAINT MONO (-560 -1190);
FORCEPROP 2 LASTPIN (300 -1250) $PN 28
J 0
(310 -1240);
DISPLAY 0.680851 (310 -1240);
PAINT MONO (310 -1240);
FORCEPROP 2 LASTPIN (-550 -1350) $PN 33
J 2
(-560 -1340);
DISPLAY 0.680851 (-560 -1340);
PAINT MONO (-560 -1340);
FORCEPROP 2 LASTPIN (-550 -1400) $PN 34
J 2
(-560 -1390);
DISPLAY 0.680851 (-560 -1390);
PAINT MONO (-560 -1390);
FORCEPROP 2 LASTPIN (-550 -900) $PN 35
J 2
(-560 -890);
DISPLAY 0.680851 (-560 -890);
PAINT MONO (-560 -890);
FORCEPROP 2 LASTPIN (300 -1400) $PN 7_10-19
J 0
(310 -1390);
DISPLAY 0.680851 (310 -1390);
PAINT MONO (310 -1390);
FORCEPROP 2 LASTPIN (300 -100) $PN 2
J 0
(310 -90);
DISPLAY 0.680851 (310 -90);
PAINT MONO (310 -90);
FORCEPROP 2 LASTPIN (300 -550) $PN 25
J 0
(310 -540);
DISPLAY 0.680851 (310 -540);
PAINT MONO (310 -540);
FORCEPROP 2 LASTPIN (-550 -150) $PN 20_24
J 2
(-560 -140);
DISPLAY 0.680851 (-560 -140);
PAINT MONO (-560 -140);
FORCEPROP 2 LASTPIN (-550 -1100) $PN 29
J 2
(-560 -1090);
DISPLAY 0.680851 (-560 -1090);
PAINT MONO (-560 -1090);
FORCEPROP 2 LASTPIN (300 -750) $PN 11_18
J 0
(310 -740);
DISPLAY 0.680851 (310 -740);
PAINT MONO (310 -740);
FORCEPROP 2 LASTPIN (-550 -1000) $PN 36
J 2
(-560 -990);
DISPLAY 0.680851 (-560 -990);
PAINT MONO (-560 -990);
FORCEPROP 2 LASTPIN (-550 -350) $PN 4
J 2
(-560 -340);
DISPLAY 0.680851 (-560 -340);
PAINT MONO (-560 -340);
FORCEPROP 2 LASTPIN (-550 -300) $PN 5
J 2
(-560 -290);
DISPLAY 0.680851 (-560 -290);
PAINT MONO (-560 -290);
FORCEPROP 2 LASTPIN (-550 -100) $PN 3
J 2
(-560 -90);
DISPLAY 0.680851 (-560 -90);
PAINT MONO (-560 -90);
FORCEPROP 2 LASTPIN (300 -1200) $PN 31
J 0
(310 -1190);
DISPLAY 0.680851 (310 -1190);
PAINT MONO (310 -1190);
FORCEPROP 2 LAST SEC_TYPE 
J 0
(-400 275);
DISPLAY 1.021277 (-400 275);
DISPLAY INVISIBLE (-400 275);
FORCEPROP 2 LAST CDS_LIB pure_quanta
J 0
(-100 -750);
DISPLAY INVISIBLE (-100 -750);
FORCEPROP 1 LAST NEEDS_NO_SIZE TRUE
J 0
(-100 -750);
DISPLAY 0.723404 (-100 -750);
PAINT GREEN (-100 -750);
DISPLAY INVISIBLE (-100 -750);
FORCEPROP 1 LAST CDS_LMAN_SYM_OUTLINE -300,700,250,-700
J 0
(-100 -750);
DISPLAY 0.468085 (-100 -750);
PAINT GREEN (-100 -750);
DISPLAY INVISIBLE (-100 -750);
FORCEPROP 1 LAST PATH I95
J 0
(-100 -750);
DISPLAY 0.723404 (-100 -750);
PAINT GREEN (-100 -750);
DISPLAY INVISIBLE (-100 -750);
FORCEPROP 2 LAST SEC 1
J 0
(-400 275);
DISPLAY 0.680851 (-400 275);
PAINT MONO (-400 275);
DISPLAY INVISIBLE (-400 275);
FORCEADD GND..1
(-4525 600);
FORCEPROP 3 LASTPIN (-4525 650) SIG_NAME GND\g
J 0
(-4515 660);
DISPLAY 0.659574 (-4515 660);
PAINT MONO (-4515 660);
DISPLAY INVISIBLE (-4515 660);
FORCEPROP 1 LAST HDL_POWER GND
J 0
(-4525 750);
DISPLAY 0.872340 (-4525 750);
PAINT GREEN (-4525 750);
DISPLAY INVISIBLE (-4525 750);
FORCEPROP 1 LAST SIZE 1B
J 0
(-4450 550);
DISPLAY 0.872340 (-4450 550);
PAINT AQUA (-4450 550);
DISPLAY INVISIBLE (-4450 550);
FORCEPROP 2 LAST CDS_LIB logical_power
J 0
(-4525 600);
DISPLAY INVISIBLE (-4525 600);
FORCEPROP 1 LAST PATH I96
J 0
(-4450 600);
DISPLAY 0.872340 (-4450 600);
PAINT AQUA (-4450 600);
DISPLAY INVISIBLE (-4450 600);
FORCEADD Q_CAP..1
(-4525 850);
FORCEPROP 1 LAST PART_NUMBER CH4106K1B01
J 0
(-4475 700);
DISPLAY 0.787234 (-4475 700);
DISPLAY INVISIBLE (-4475 700);
FORCEPROP 1 LAST VOLTAGE 50V
J 0
(-4475 850);
DISPLAY 0.787234 (-4475 850);
FORCEPROP 1 LAST VALUE 100NF
J 0
(-4475 900);
DISPLAY 0.787234 (-4475 900);
FORCEPROP 1 LAST TOLERANCE 10%
J 0
(-4475 800);
DISPLAY 0.787234 (-4475 800);
FORCEPROP 1 LAST MATERIAL X7R
J 0
(-4475 750);
DISPLAY 0.787234 (-4475 750);
FORCEPROP 1 LAST PACK_TYPE C0402
J 0
(-4475 650);
DISPLAY 0.787234 (-4475 650);
FORCEPROP 1 LAST LOCATION PC1649
J 0
(-4475 950);
DISPLAY 0.787234 (-4475 950);
FORCEPROP 1 LASTPIN (-4525 950) $PN 1
J 0
(-4515 930);
DISPLAY 0.787234 (-4515 930);
PAINT MONO (-4515 930);
FORCEPROP 1 LASTPIN (-4525 750) $PN 2
J 0
(-4515 730);
DISPLAY 0.787234 (-4515 730);
PAINT MONO (-4515 730);
FORCEPROP 2 LAST CDS_LIB pure_quanta
J 0
(-4525 850);
DISPLAY INVISIBLE (-4525 850);
FORCEPROP 1 LAST PATH I97
J 0
(-4475 1000);
DISPLAY 0.978723 (-4475 1000);
PAINT WHITE (-4475 1000);
DISPLAY INVISIBLE (-4475 1000);
FORCEPROP 0 LAST $SEC 1
J 0
(-4475 1000);
DISPLAY 0.680851 (-4475 1000);
PAINT MONO (-4475 1000);
DISPLAY INVISIBLE (-4475 1000);
FORCEPROP 0 LAST CDS_SEC 1
J 0
(-4475 1000);
DISPLAY 1.021277 (-4475 1000);
DISPLAY INVISIBLE (-4475 1000);
FORCEADD Q_INDUCTOR..1
(-4300 1075);
FORCEPROP 1 LAST PART_NUMBER CV+10G0MZ04
J 0
(-4425 1185);
DISPLAY 0.617021 (-4425 1185);
PAINT BLUE (-4425 1185);
DISPLAY INVISIBLE (-4425 1185);
FORCEPROP 1 LAST MATERIAL IND
J 0
(-4425 1130);
DISPLAY 0.617021 (-4425 1130);
PAINT SKYBLUE (-4425 1130);
FORCEPROP 2 LAST VALUE 100NH/16A
J 0
(-4425 1325);
DISPLAY 0.617021 (-4425 1325);
PAINT SKYBLUE (-4425 1325);
FORCEPROP 2 LAST PACK_TYPE SMLF
J 0
(-4425 1275);
DISPLAY 0.617021 (-4425 1275);
PAINT SKYBLUE (-4425 1275);
FORCEPROP 1 LAST LOCATION PL45
J 0
(-4425 1235);
DISPLAY 0.617021 (-4425 1235);
PAINT AQUA (-4425 1235);
FORCEPROP 0 LASTPIN (-4400 1050) $PN 1
J 2
(-4410 1060);
DISPLAY 0.617021 (-4410 1060);
PAINT MONO (-4410 1060);
FORCEPROP 0 LASTPIN (-4200 1050) $PN 2
J 0
(-4190 1060);
DISPLAY 0.617021 (-4190 1060);
PAINT MONO (-4190 1060);
FORCEPROP 1 LAST NEEDS_NO_SIZE TRUE
J 0
(-4300 1075);
DISPLAY 0.468085 (-4300 1075);
PAINT GREEN (-4300 1075);
DISPLAY INVISIBLE (-4300 1075);
FORCEPROP 2 LAST CDS_LIB pure_quanta
J 0
(-4300 1075);
DISPLAY INVISIBLE (-4300 1075);
FORCEPROP 1 LAST PATH I98
J 0
(-4225 1130);
DISPLAY 0.723404 (-4225 1130);
PAINT GREEN (-4225 1130);
DISPLAY INVISIBLE (-4225 1130);
FORCEPROP 0 LAST $SEC 1
J 0
(-4425 1375);
DISPLAY 0.680851 (-4425 1375);
PAINT MONO (-4425 1375);
DISPLAY INVISIBLE (-4425 1375);
FORCEPROP 0 LAST CDS_SEC 1
J 0
(-4425 1375);
DISPLAY 1.021277 (-4425 1375);
DISPLAY INVISIBLE (-4425 1375);
FORCEADD UNIVERSAL_POWER..1
(-4525 1475);
FORCEPROP 3 LASTPIN (-4525 1425) SIG_NAME P12V_AUX\g
J 0
(-4515 1435);
DISPLAY 0.659574 (-4515 1435);
PAINT MONO (-4515 1435);
DISPLAY INVISIBLE (-4515 1435);
FORCEPROP 1 LAST HDL_POWER P12V_AUX
J 1
(-4525 1525);
DISPLAY 0.617021 (-4525 1525);
PAINT GREEN (-4525 1525);
FORCEPROP 2 LAST CDS_LIB logical_power
J 0
(-4525 1475);
PAINT MONO (-4525 1475);
DISPLAY INVISIBLE (-4525 1475);
FORCEPROP 1 LAST PATH I99
J 0
(-4475 1500);
DISPLAY 0.872340 (-4475 1500);
PAINT AQUA (-4475 1500);
DISPLAY INVISIBLE (-4475 1500);
FORCEADD DNS..1
(-3775 -975);
PAINT RED (-3775 -975);
FORCEPROP 1 LAST COMMENT_BODY TRUE
J 0
(-3775 -975);
DISPLAY INVISIBLE (-3775 -975);
FORCEPROP 2 LAST CDS_LIB mstr_misc
J 0
(-3775 -975);
DISPLAY INVISIBLE (-3775 -975);
FORCEADD DNS..1
(-3775 -1550);
PAINT RED (-3775 -1550);
FORCEPROP 1 LAST COMMENT_BODY TRUE
J 0
(-3775 -1550);
DISPLAY INVISIBLE (-3775 -1550);
FORCEPROP 2 LAST CDS_LIB mstr_misc
J 0
(-3775 -1550);
DISPLAY INVISIBLE (-3775 -1550);
FORCEADD DNS..1
(-1775 -1350);
PAINT RED (-1775 -1350);
FORCEPROP 1 LAST COMMENT_BODY TRUE
J 0
(-1775 -1350);
DISPLAY INVISIBLE (-1775 -1350);
FORCEPROP 2 LAST CDS_LIB mstr_misc
J 0
(-1775 -1350);
DISPLAY INVISIBLE (-1775 -1350);
FORCEADD DNS..1
(825 -1275);
PAINT RED (825 -1275);
FORCEPROP 2 LAST CDS_LIB mstr_misc
J 0
(825 -1275);
DISPLAY INVISIBLE (825 -1275);
FORCEPROP 1 LAST COMMENT_BODY TRUE
J 0
(825 -1275);
DISPLAY INVISIBLE (825 -1275);
FORCEADD QUANTA_TITLE_BLOCK_C..1
(4500 -3400);
FORCEPROP 0 LAST CDS_CON_LAST_MODIFIED Fri Aug 25 14:04:30 2023
J 0
(2615 -3385);
DISPLAY INVISIBLE (2615 -3385);
FORCEPROP 1 LAST CUSTOM_TXT_CDS <CON_LAST_MODIFIED>
J 0
(2615 -3385);
DISPLAY 0.978723 (2615 -3385);
FORCEPROP 2 LAST CUSTOM_TXT_CDS <XR_PAGE_TITLE>
J 0
(-3390 1850);
DISPLAY 0.638298 (-3390 1850);
PAINT PINK (-3390 1850);
DISPLAY INVISIBLE (-3390 1850);
FORCEPROP 1 LAST CUSTOM_TXT_CDS <NAME_2>
J 0
(1325 -3350);
FORCEPROP 1 LAST CUSTOM_TXT_CDS <NAME_1>
J 0
(1325 -3225);
FORCEPROP 1 LAST CUSTOM_TXT_CDS <Q_NUMBER>
J 0
(3097 -3297);
DISPLAY 1.212766 (3097 -3297);
FORCEPROP 1 LAST CUSTOM_TXT_CDS <Q_PROJ>
J 0
(2118 -3298);
DISPLAY 1.212766 (2118 -3298);
FORCEPROP 1 LAST CUSTOM_TXT_CDS <Q_REV>
J 0
(4316 -3297);
DISPLAY 1.212766 (4316 -3297);
FORCEPROP 1 LAST CUSTOM_TXT_CDS <CON_PAGE_NUM> OF <CON_TOTAL_PAGES>
J 0
(4054 -3382);
DISPLAY 0.978723 (4054 -3382);
FORCEPROP 1 LAST Q_TITLE NCP3284/P3V3_AUX
J 0
(-4775 -3350);
DISPLAY 2.446809 (-4775 -3350);
PAINT GREEN (-4775 -3350);
FORCEPROP 1 LAST Q_DEPT 
J 1
(725 -3350);
DISPLAY 1.957447 (725 -3350);
PAINT GREEN (725 -3350);
FORCEPROP 2 LAST CDS_XR_PAGE_TITLE CR-259 : @S9S_MB_2U_LIB.S9S_MB_2U(SCH_1):PAGE259
J 0
(-3390 1850);
DISPLAY 0.638298 (-3390 1850);
PAINT PINK (-3390 1850);
DISPLAY INVISIBLE (-3390 1850);
FORCEPROP 2 LAST CDS_LIB pure_quanta
J 0
(4500 -3400);
DISPLAY INVISIBLE (4500 -3400);
FORCEPROP 1 LAST CDS_LMAN_SYM_OUTLINE -9475,6775,100,-125
J 0
(4500 -3400);
DISPLAY 0.468085 (4500 -3400);
PAINT GREEN (4500 -3400);
DISPLAY INVISIBLE (4500 -3400);
FORCEPROP 2 LAST PAGE_BORDER TRUE
J 0
(-3390 1850);
DISPLAY 0.638298 (-3390 1850);
PAINT PINK (-3390 1850);
DISPLAY INVISIBLE (-3390 1850);
FORCEPROP 1 LAST COMMENT_BODY TRUE
J 0
(4512 -3413);
DISPLAY 0.978723 (4512 -3413);
PAINT GREEN (4512 -3413);
DISPLAY INVISIBLE (4512 -3413);
WIRE 16 -1 (-3825 -850)(-3825 -675);
WIRE 16 -1 (-4525 1050)(-4525 1425);
WIRE 16 -1 (-4525 950)(-4525 1050);
WIRE 16 -1 (-4400 1050)(-4525 1050);
WIRE 16 -1 (-1150 750)(-1150 675);
WIRE 16 -1 (1075 -1250)(1075 -1200);
WIRE 16 -1 (925 -1250)(1075 -1250);
WIRE 16 -1 (4175 -750)(4175 -500);
WIRE 16 -1 (3725 -750)(4175 -750);
WIRE 16 -1 (4175 -750)(4175 -1550);
WIRE 16 -1 (900 375)(900 300);
WIRE 16 -1 (-3825 -1775)(-3825 -1625);
WIRE 16 -1 (-3225 -1850)(-3225 -1700);
WIRE 16 -1 (-4050 -50)(-4050 -100);
WIRE 16 -1 (-4050 -50)(-3725 -50);
WIRE 16 -1 (-4050 -50)(-4050 100);
WIRE 16 -1 (-2150 -1350)(-2150 -1325);
WIRE 16 -1 (-2050 -800)(-2050 -725);
WIRE 16 -1 (-1750 -1425)(-1750 -1475);
WIRE 16 -1 (-1350 -1575)(-1350 -1525);
WIRE 16 -1 (-1625 -800)(-1625 -725);
WIRE 16 -1 (-4525 650)(-4525 750);
WIRE 16 -1 (-3975 525)(-3975 600);
WIRE 16 -1 (-900 375)(-900 250);
WIRE 16 -1 (350 -1400)(350 -1450);
WIRE 16 -1 (350 -1350)(350 -1400);
WIRE 16 -1 (300 -1400)(350 -1400);
WIRE 16 -1 (300 -1200)(500 -1200);
WIRE 16 -1 (1200 -1950)(1200 -1825);
WIRE 16 -1 (3725 -1300)(3725 -1250);
WIRE 16 2175 (-3375 -450)(-2472 -450);
WIRE 16 2175 (-2472 -450)(-2472 -1950);
WIRE 16 2175 (-3375 -450)(-3375 -1950);
WIRE 16 2175 (-3375 -1950)(-2472 -1950);
WIRE 16 -1 (-3825 -1425)(-3825 -1350);
WIRE 16 -1 (-3825 -1350)(-3825 -1050);
WIRE 16 -1 (-3825 -1350)(-3275 -1350);
WIRE 16 -1 (-3275 -1125)(-3275 -1350);
WIRE 16 -1 (-2900 -775)(-2750 -775);
WIRE 16 -1 (-3275 -1350)(-3225 -1350);
WIRE 16 -1 (-3225 -1500)(-3225 -1350);
WIRE 16 -1 (-2750 -1350)(-3225 -1350);
WIRE 16 -1 (-2750 -775)(-2750 -1350);
WIRE 16 -1 (-2750 -1350)(-2250 -1350);
WIRE 16 -1 (-2250 -1350)(-2250 -950);
WIRE 16 -1 (-2250 -950)(-1225 -950);
WIRE 16 -1 (-1225 -950)(-1225 -550);
WIRE 16 -1 (-1225 -550)(-550 -550);
FORCEPROP 2 LAST SIG_NAME P3V3_AUX_EN
J 0
(-1085 -540);
DISPLAY 0.617021 (-1085 -540);
WIRE 16 -1 (-550 -1350)(-1075 -1350);
FORCEPROP 2 LAST SIG_NAME NC_PU9_1
J 0
(-1085 -1340);
DISPLAY 0.617021 (-1085 -1340);
WIRE 16 -1 (-3275 -375)(-3800 -375);
FORCEPROP 2 LAST SIG_NAME MB0_P12V_STBY_PWRGD
J 0
(-3785 -365);
DISPLAY 0.638298 (-3785 -365);
WIRE 16 -1 (-3275 -925)(-3275 -775);
WIRE 16 -1 (-3275 -775)(-3150 -775);
WIRE 16 -1 (-3275 -775)(-3275 -375);
WIRE 16 -1 (-2150 -1000)(-2150 -1125);
WIRE 16 -1 (-550 -1000)(-2150 -1000);
FORCEPROP 2 LAST SIG_NAME P3V3_AUX_MODE
J 0
(-1085 -990);
DISPLAY 0.617021 (-1085 -990);
WIRE 16 3135 (4125 1950)(2725 1950);
WIRE 16 3135 (4125 2525)(4125 1950);
WIRE 16 3135 (2725 1950)(2725 2525);
WIRE 16 3135 (2725 2525)(4125 2525);
WIRE 16 -1 (2200 -1850)(2550 -1850);
WIRE 16 -1 (2200 -1550)(2550 -1550);
WIRE 16 -1 (2550 -1850)(2550 -1550);
WIRE 16 -1 (2550 -1550)(4175 -1550);
WIRE 16 -1 (3725 -875)(3725 -750);
WIRE 16 -1 (3325 -875)(3325 -750);
WIRE 16 -1 (3725 -750)(3325 -750);
WIRE 16 -1 (2950 -875)(2950 -750);
WIRE 16 -1 (3325 -750)(2950 -750);
WIRE 16 -1 (2550 -850)(2550 -750);
WIRE 16 -1 (2950 -750)(2550 -750);
WIRE 16 -1 (2100 -875)(2100 -750);
WIRE 16 -1 (2100 -750)(2550 -750);
WIRE 16 -1 (1650 -875)(1650 -750);
WIRE 16 -1 (2100 -750)(1650 -750);
WIRE 16 -1 (1525 -750)(1650 -750);
WIRE 16 -1 (1650 -1250)(1650 -1075);
WIRE 16 -1 (3725 -1250)(3725 -1075);
WIRE 16 -1 (3325 -1075)(3325 -1250);
WIRE 16 -1 (3725 -1250)(3325 -1250);
WIRE 16 -1 (2100 -1250)(1650 -1250);
WIRE 16 -1 (2100 -1075)(2100 -1250);
WIRE 16 -1 (2550 -1250)(2100 -1250);
WIRE 16 -1 (2550 -1050)(2550 -1250);
WIRE 16 -1 (2950 -1075)(2950 -1250);
WIRE 16 -1 (3325 -1250)(2950 -1250);
WIRE 16 -1 (2950 -1250)(2550 -1250);
WIRE 16 -1 (2000 -1850)(1650 -1850);
WIRE 16 -1 (1650 -1850)(1650 -1550);
WIRE 16 -1 (2000 -1550)(1650 -1550);
WIRE 16 -1 (1200 -1625)(1200 -1550);
WIRE 16 -1 (1200 -1550)(1650 -1550);
WIRE 16 -1 (1200 -1550)(1200 -950);
WIRE 16 -1 (300 -950)(1200 -950);
FORCEPROP 2 LAST SIG_NAME P3V3_AUX_FB
J 0
(440 -940);
DISPLAY 0.617021 (440 -940);
WIRE 16 -1 (1150 -350)(900 -350);
WIRE 16 -1 (825 -550)(1150 -550);
WIRE 16 -1 (1150 -550)(1150 -350);
FORCEPROP 2 LAST SIG_NAME SW_P3V3_AUX_BOOT_R
R 3
J 0
(1165 -115);
DISPLAY 0.617021 (1165 -115);
WIRE 16 -1 (300 -750)(1325 -750);
FORCEPROP 2 LAST SIG_NAME SW_P3V3_AUX_SW
J 0
(440 -740);
DISPLAY 0.617021 (440 -740);
WIRE 16 -1 (300 -550)(625 -550);
FORCEPROP 2 LAST SIG_NAME SW_P3V3_AUX_BOOTR
J 0
(190 -590);
DISPLAY 0.617021 (190 -590);
WIRE 16 -1 (1350 -100)(900 -100);
WIRE 16 -1 (900 -100)(900 100);
WIRE 16 -1 (300 -100)(900 -100);
FORCEPROP 2 LAST SIG_NAME PWRGD_P3V3_AUX
J 0
(440 -90);
DISPLAY 0.617021 (440 -90);
WIRE 16 -1 (300 -350)(700 -350);
FORCEPROP 2 LAST SIG_NAME SW_P3V3_AUX_BOOT
J 0
(190 -390);
DISPLAY 0.617021 (190 -390);
WIRE 16 -1 (725 -1250)(300 -1250);
FORCEPROP 2 LAST SIG_NAME P3V3_AUX_VOS
J 0
(440 -1290);
DISPLAY 0.617021 (440 -1290);
WIRE 16 -1 (300 -1350)(350 -1350);
WIRE 16 -1 (-1150 -100)(-550 -100);
WIRE 16 -1 (-1150 675)(-1150 -100);
WIRE 16 -1 (-1150 675)(-900 675);
WIRE 16 -1 (-900 675)(-900 575);
WIRE 16 -1 (-550 -150)(-1375 -150);
WIRE 16 -1 (-1375 1050)(-1375 -150);
WIRE 16 -1 (-1725 1050)(-1725 950);
WIRE 16 -1 (-1375 1050)(-1725 1050);
WIRE 16 -1 (-2050 1050)(-2050 950);
WIRE 16 -1 (-1725 1050)(-2050 1050);
WIRE 16 -1 (-2375 950)(-2375 1050);
WIRE 16 -1 (-2375 1050)(-2050 1050);
WIRE 16 -1 (-2700 1050)(-2700 950);
WIRE 16 -1 (-2700 1050)(-2375 1050);
WIRE 16 -1 (-3025 1050)(-3025 950);
WIRE 16 -1 (-3025 1050)(-2700 1050);
WIRE 16 -1 (-3350 1050)(-3350 950);
WIRE 16 -1 (-3350 1050)(-3025 1050);
FORCEPROP 2 LAST SIG_NAME SW_P3V3_AUX_FLT
J 0
(-3110 1050);
DISPLAY 0.617021 (-3110 1050);
WIRE 16 -1 (-3675 950)(-3675 1050);
WIRE 16 -1 (-3675 1050)(-3350 1050);
WIRE 16 -1 (-3975 950)(-3975 1050);
WIRE 16 -1 (-3975 1050)(-3675 1050);
WIRE 16 -1 (-4050 1050)(-4200 1050);
WIRE 16 -1 (-3975 1050)(-4050 1050);
WIRE 16 -1 (-4050 300)(-4050 375);
WIRE 16 -1 (-4050 1050)(-4050 375);
WIRE 16 -1 (-4050 375)(-3725 375);
WIRE 16 -1 (-3725 375)(-3725 300);
WIRE 16 -1 (-3725 375)(-3400 375);
WIRE 16 -1 (-3400 375)(-3400 300);
WIRE 16 -1 (-3400 375)(-3075 375);
WIRE 16 -1 (-3075 375)(-3075 300);
WIRE 16 -1 (-3075 375)(-2750 375);
WIRE 16 -1 (-2750 375)(-2750 300);
WIRE 16 -1 (-2750 375)(-2425 375);
WIRE 16 -1 (-2425 375)(-2425 300);
WIRE 16 -1 (-2425 375)(-2100 375);
WIRE 16 -1 (-2100 375)(-2100 300);
WIRE 16 -1 (-1725 750)(-1725 600);
WIRE 16 -1 (-2050 750)(-2050 600);
WIRE 16 -1 (-1725 600)(-2050 600);
WIRE 16 -1 (-2375 750)(-2375 600);
WIRE 16 -1 (-2375 600)(-2050 600);
WIRE 16 -1 (-2700 600)(-2700 750);
WIRE 16 -1 (-2700 600)(-2375 600);
WIRE 16 -1 (-3025 600)(-3025 750);
WIRE 16 -1 (-3025 600)(-2700 600);
WIRE 16 -1 (-3350 600)(-3350 750);
WIRE 16 -1 (-3350 600)(-3025 600);
WIRE 16 -1 (-3675 600)(-3675 750);
WIRE 16 -1 (-3675 600)(-3350 600);
WIRE 16 -1 (-3975 600)(-3975 750);
WIRE 16 -1 (-3975 600)(-3675 600);
WIRE 16 -1 (-2100 100)(-2100 -50);
WIRE 16 -1 (-2425 -50)(-2100 -50);
WIRE 16 -1 (-2425 -50)(-2425 100);
WIRE 16 -1 (-2750 -50)(-2425 -50);
WIRE 16 -1 (-2750 -50)(-2750 100);
WIRE 16 -1 (-3075 -50)(-2750 -50);
WIRE 16 -1 (-3075 100)(-3075 -50);
WIRE 16 -1 (-3400 -50)(-3075 -50);
WIRE 16 -1 (-3400 -50)(-3400 100);
WIRE 16 -1 (-3725 -50)(-3400 -50);
WIRE 16 -1 (-3725 -50)(-3725 100);
WIRE 16 2175 (-2800 -225)(-1625 -225);
WIRE 16 2175 (-1625 400)(-1625 -225);
WIRE 16 2175 (-2800 400)(-2800 -225);
WIRE 16 2175 (-2800 400)(-1625 400);
WIRE 16 -1 (-1625 -400)(-1625 -525);
WIRE 16 -1 (-1700 -400)(-1625 -400);
WIRE 16 -1 (-675 -400)(-1625 -400);
FORCEPROP 2 LAST SIG_NAME P3V3_AUX_VCC
J 0
(-1085 -390);
DISPLAY 0.617021 (-1085 -390);
WIRE 16 -1 (-675 -350)(-675 -400);
WIRE 16 -1 (-550 -350)(-675 -350);
WIRE 16 -1 (-550 -700)(-1075 -700);
FORCEPROP 2 LAST SIG_NAME NC_PU9_3
J 0
(-1085 -690);
DISPLAY 0.617021 (-1085 -690);
WIRE 16 -1 (-550 -750)(-1075 -750);
FORCEPROP 2 LAST SIG_NAME NC_PU9_4
J 0
(-1085 -740);
DISPLAY 0.617021 (-1085 -740);
WIRE 16 -1 (-550 -900)(-1075 -900);
FORCEPROP 2 LAST SIG_NAME NC_HICCUP
J 0
(-1085 -890);
DISPLAY 0.617021 (-1085 -890);
WIRE 16 -1 (-550 -1400)(-1075 -1400);
FORCEPROP 2 LAST SIG_NAME NC_PU9_2
J 0
(-1085 -1390);
DISPLAY 0.617021 (-1085 -1390);
WIRE 16 -1 (-2050 -300)(-550 -300);
FORCEPROP 2 LAST SIG_NAME P3V3_AUX_VDRV
J 0
(-1085 -290);
DISPLAY 0.617021 (-1085 -290);
WIRE 16 -1 (-2050 -400)(-2050 -300);
WIRE 16 -1 (-2050 -400)(-1900 -400);
WIRE 16 -1 (-2050 -525)(-2050 -400);
WIRE 16 -1 (-1350 -1200)(-550 -1200);
WIRE 16 -1 (-1350 -1325)(-1350 -1200);
FORCEPROP 2 LAST SIG_NAME P3V3_AUX_ILIM
J 0
(-1085 -1190);
DISPLAY 0.617021 (-1085 -1190);
WIRE 16 -1 (-1750 -1100)(-550 -1100);
FORCEPROP 2 LAST SIG_NAME P3V3_AUX_SS
J 0
(-1085 -1090);
DISPLAY 0.617021 (-1085 -1090);
WIRE 16 -1 (-1750 -1225)(-1750 -1100);
WIRE 16 2175 (-4425 -2200)(-3572 -2200);
WIRE 16 2175 (-3572 -1850)(-3572 -2200);
WIRE 16 2175 (-4425 -1850)(-4425 -2200);
WIRE 16 2175 (-4425 -1850)(-3572 -1850);
WIRE 16 2175 (-4425 -2975)(-2825 -2975);
WIRE 16 2175 (-2825 -2250)(-2825 -2975);
WIRE 16 2175 (-4425 -2250)(-4425 -2975);
WIRE 16 2175 (-4425 -2250)(-2825 -2250);
DOT 1 (-3225 -1350);
DOT 1 (-3275 -1350);
DOT 1 (-3825 -1350);
DOT 1 (-2750 -1350);
DOT 1 (-3275 -775);
DOT 1 (4175 -750);
DOT 1 (3725 -750);
DOT 1 (3325 -750);
DOT 1 (3725 -1250);
DOT 1 (3325 -1250);
DOT 1 (2950 -750);
DOT 1 (2550 -750);
DOT 1 (2100 -750);
DOT 1 (2950 -1250);
DOT 1 (2550 -1550);
DOT 1 (2550 -1250);
DOT 1 (2100 -1250);
DOT 1 (1650 -750);
DOT 1 (1650 -1550);
DOT 1 (1200 -1550);
DOT 1 (900 -100);
DOT 1 (350 -1400);
DOT 1 (-1725 1050);
DOT 1 (-2050 1050);
DOT 1 (-1150 675);
DOT 1 (-2050 600);
DOT 1 (-2375 1050);
DOT 1 (-2700 1050);
DOT 1 (-3025 1050);
DOT 1 (-2375 600);
DOT 1 (-2425 375);
DOT 1 (-2425 -50);
DOT 1 (-2700 600);
DOT 1 (-3025 600);
DOT 1 (-2750 375);
DOT 1 (-2750 -50);
DOT 1 (-3075 375);
DOT 1 (-3075 -50);
DOT 1 (-3350 1050);
DOT 1 (-3675 1050);
DOT 1 (-3975 1050);
DOT 1 (-4050 1050);
DOT 1 (-3350 600);
DOT 1 (-3400 375);
DOT 1 (-3400 -50);
DOT 1 (-3675 600);
DOT 1 (-3975 600);
DOT 1 (-3725 375);
DOT 1 (-3725 -50);
DOT 1 (-4050 375);
DOT 1 (-4050 -50);
DOT 1 (-4525 1050);
DOT 1 (-1625 -400);
DOT 1 (-2050 -400);
FORCENOTE
20220901 ADD D145,CHANGE R1571 TO 100K,C2341 TO 0.22 UF
(-3375 -2025) 0;
DISPLAY LEFT (-3375 -2025);
DISPLAY 1.063830 (-3375 -2025);
PAINT WHITE (-3375 -2025);
FORCENOTE
20220804 CHANGE IC TABLE
(-4400 -3075) 0;
DISPLAY LEFT (-4400 -3075);
DISPLAY 1.595745 (-4400 -3075);
PAINT PINK (-4400 -3075);
FORCENOTE
TSS=4MS
(-2075 -1675) 0;
DISPLAY LEFT (-2075 -1675);
DISPLAY 1.595745 (-2075 -1675);
PAINT WHITE (-2075 -1675);
FORCENOTE
OUTPUT RIPPLE & NOISE < 50MV
(2750 2325) 0;
DISPLAY LEFT (2750 2325);
DISPLAY 1.021277 (2750 2325);
PAINT WHITE (2750 2325);
FORCENOTE
OUTPUT VOLTAGE = 3.3V+/-5%
(2750 2375) 0;
DISPLAY LEFT (2750 2375);
DISPLAY 1.021277 (2750 2375);
PAINT WHITE (2750 2375);
FORCENOTE
TRANSIENT TOLERANCE = 330MV
(2750 2275) 0;
DISPLAY LEFT (2750 2275);
DISPLAY 1.021277 (2750 2275);
PAINT WHITE (2750 2275);
FORCENOTE
OCP = 32A
(2750 2125) 0;
DISPLAY LEFT (2750 2125);
DISPLAY 1.021277 (2750 2125);
PAINT RED (2750 2125);
FORCENOTE
SLEW RATE = 2.5A/US
(2750 2075) 0;
DISPLAY LEFT (2750 2075);
DISPLAY 1.021277 (2750 2075);
PAINT WHITE (2750 2075);
FORCENOTE
DESIGN SPECIFICATION
(2750 2450) 0;
DISPLAY LEFT (2750 2450);
DISPLAY 1.021277 (2750 2450);
PAINT WHITE (2750 2450);
FORCENOTE
TDC = 19A
(2750 2225) 0;
DISPLAY LEFT (2750 2225);
DISPLAY 1.021277 (2750 2225);
PAINT RED (2750 2225);
FORCENOTE
IMAX = 21A
(2750 2175) 0;
DISPLAY LEFT (2750 2175);
DISPLAY 1.021277 (2750 2175);
PAINT RED (2750 2175);
FORCENOTE
CURRENT STEP = 10.5A
(2750 2025) 0;
DISPLAY LEFT (2750 2025);
DISPLAY 1.021277 (2750 2025);
PAINT WHITE (2750 2025);
FORCENOTE
WORK FREQUENCY = 600KHZ
(2750 1975) 0;
DISPLAY LEFT (2750 1975);
DISPLAY 1.021277 (2750 1975);
PAINT WHITE (2750 1975);
FORCENOTE
VO=0.8(1+RA/RB)=3.3V
(2800 -1825) 0;
DISPLAY LEFT (2800 -1825);
DISPLAY 1.021277 (2800 -1825);
PAINT SKYBLUE (2800 -1825);
FORCENOTE
DCR=1.5M OHM
(1650 -550) 0;
DISPLAY LEFT (1650 -550);
DISPLAY 1.021277 (1650 -550);
FORCENOTE
 EM-15AM17VG1-QS
(1600 -325) 0;
DISPLAY LEFT (1600 -325);
DISPLAY 1.021277 (1600 -325);
FORCENOTE
ISAT=53A@100C
(1650 -475) 0;
DISPLAY LEFT (1650 -475);
DISPLAY 1.021277 (1650 -475);
FORCENOTE
14.3*12.9*8.0
(1650 -400) 0;
DISPLAY LEFT (1650 -400);
DISPLAY 1.021277 (1650 -400);
FORCENOTE
RA
(1700 -1500) 0;
DISPLAY LEFT (1700 -1500);
DISPLAY 1.021277 (1700 -1500);
FORCENOTE
RB
(1000 -1775) 0;
DISPLAY LEFT (1000 -1775);
DISPLAY 1.021277 (1000 -1775);
FORCENOTE
P3V3_AUX
(-1350 2200) 0;
DISPLAY LEFT (-1350 2200);
DISPLAY 4.914894 (-1350 2200);
PAINT YELLOW (-1350 2200);
FORCENOTE
ESR=9.5M OHM
(-3625 625) 0;
DISPLAY LEFT (-3625 625);
DISPLAY 0.404255 (-3625 625);
FORCENOTE
ESR=9.5M OHM
(-3925 625) 0;
DISPLAY LEFT (-3925 625);
DISPLAY 0.404255 (-3925 625);
FORCENOTE
BASE ON POC
(-2750 -100) 0;
DISPLAY LEFT (-2750 -100);
DISPLAY 1.021277 (-2750 -100);
FORCENOTE
TO IMPROVE INPUT RIPPLE
(-2750 -175) 0;
DISPLAY LEFT (-2750 -175);
DISPLAY 1.021277 (-2750 -175);
FORCENOTE
IC TABLE
(-4400 -1950) 0;
DISPLAY LEFT (-4400 -1950);
DISPLAY 1.170213 (-4400 -1950);
PAINT WHITE (-4400 -1950);
FORCENOTE
1ST AL003889000
(-4400 -2025) 0;
DISPLAY LEFT (-4400 -2025);
DISPLAY 1.021277 (-4400 -2025);
PAINT WHITE (-4400 -2025);
FORCENOTE
PC8   CHANGE TO CH5103K1900
(-4175 -2900) 0;
DISPLAY LEFT (-4175 -2900);
DISPLAY 1.021277 (-4175 -2900);
PAINT WHITE (-4175 -2900);
FORCENOTE
PC569 CHANGE TO CH0106F0B00
(-4175 -2825) 0;
DISPLAY LEFT (-4175 -2825);
DISPLAY 1.021277 (-4175 -2825);
PAINT WHITE (-4175 -2825);
FORCENOTE
PR836 CHANGE TO CS21002FB06
(-4175 -2750) 0;
DISPLAY LEFT (-4175 -2750);
DISPLAY 1.021277 (-4175 -2750);
PAINT WHITE (-4175 -2750);
FORCENOTE
PR834 CHANGE TO CS31622FB02
(-4175 -2650) 0;
DISPLAY LEFT (-4175 -2650);
DISPLAY 1.021277 (-4175 -2650);
PAINT WHITE (-4175 -2650);
FORCENOTE
PR831 CHANGE TO CS35602BB01
(-4175 -2575) 0;
DISPLAY LEFT (-4175 -2575);
DISPLAY 1.021277 (-4175 -2575);
PAINT WHITE (-4175 -2575);
FORCENOTE
R&C TABLE
(-4400 -2350) 0;
DISPLAY LEFT (-4400 -2350);
DISPLAY 1.170213 (-4400 -2350);
PAINT WHITE (-4400 -2350);
FORCENOTE
PR830 CHANGE TO CS31242BB10
(-4175 -2500) 0;
DISPLAY LEFT (-4175 -2500);
DISPLAY 1.021277 (-4175 -2500);
PAINT WHITE (-4175 -2500);
FORCENOTE
3RD AL003284002
(-4400 -2175) 0;
DISPLAY LEFT (-4400 -2175);
DISPLAY 1.021277 (-4400 -2175);
PAINT WHITE (-4400 -2175);
FORCENOTE
2ND AL003884000
(-4400 -2100) 0;
DISPLAY LEFT (-4400 -2100);
DISPLAY 1.021277 (-4400 -2100);
PAINT WHITE (-4400 -2100);
FORCENOTE
3RD 
(-4400 -2750) 0;
DISPLAY LEFT (-4400 -2750);
DISPLAY 1.170213 (-4400 -2750);
PAINT WHITE (-4400 -2750);
FORCENOTE
1ST 
(-4400 -2425) 0;
DISPLAY LEFT (-4400 -2425);
DISPLAY 1.170213 (-4400 -2425);
PAINT WHITE (-4400 -2425);
FORCENOTE
2ND 
(-4400 -2500) 0;
DISPLAY LEFT (-4400 -2500);
DISPLAY 1.170213 (-4400 -2500);
PAINT WHITE (-4400 -2500);
QUIT
